G04 ================== begin FILE IDENTIFICATION RECORD ==================*
G04 Layout Name:  15105-sa.brd*
G04 Film Name:    DP_REF_L8*
G04 File Format:  Gerber RS274X*
G04 File Origin:  Cadence Allegro 16.5-S056*
G04 Origin Date:  Wed Nov 16 02:02:47 2016*
G04 *
G04 Layer:  BOARD GEOMETRY/DP_REF_L8_TBL*
G04 Layer:  BOARD GEOMETRY/DP_REF_L8_BOTTOM*
G04 Layer:  BOARD GEOMETRY/PANEL_OUTLINE*
G04 *
G04 Offset:    (0.00 0.00)*
G04 Mirror:    No*
G04 Mode:      Positive*
G04 Rotation:  0*
G04 FullContactRelief:  No*
G04 UndefLineWidth:     6.00*
G04 ================== end FILE IDENTIFICATION RECORD ====================*
%FSLAX35Y35*MOIN*%
%IR0*IPPOS*OFA0.00000B0.00000*MIA0B0*SFA1.00000B1.00000*%
%ADD10C,.02*%
%ADD11C,.006*%
%ADD12C,.00538*%
G75*
%LPD*%
G75*
G54D10*
G01X1479970Y759338D02*
X2249970D01*
G01X1479970Y863288D02*
Y759338D01*
G01Y793988D02*
X2249970D01*
G01X1479970Y828638D02*
X2249970D01*
G01X1479970Y863288D02*
X2249970D01*
G01X1654970D02*
Y759338D01*
G01X1934970Y863288D02*
Y759338D01*
G01X2039970Y863288D02*
Y759338D01*
G01X2249970Y863288D02*
Y759338D01*
G54D11*
G01X-27072Y-83981D02*
Y-101481D01*
G01X-32094Y-83981D02*
X-22050D01*
G01X-13284Y-101481D02*
Y-83981D01*
G01Y-92439D02*
X-12192Y-90981D01*
X-11100Y-90106D01*
X-9354Y-89815D01*
X-8044Y-90106D01*
X-6515Y-91273D01*
X-5860Y-93023D01*
Y-101481D01*
G01X7928Y-89815D02*
Y-101481D01*
G01Y-85148D02*
X7491Y-84856D01*
Y-84273D01*
X7928Y-83981D01*
X8365Y-84273D01*
Y-84856D01*
X7928Y-85148D01*
G01X22153Y-99440D02*
X23245Y-100606D01*
X24773Y-101481D01*
X26083D01*
X27393Y-100898D01*
X28266Y-100023D01*
X28703Y-98857D01*
X28485Y-97106D01*
X27611Y-96231D01*
X23681Y-94481D01*
X22808Y-92439D01*
X23245Y-90981D01*
X24118Y-90106D01*
X25428Y-89815D01*
X26738Y-90106D01*
X28048Y-90981D01*
G01X57371Y-105856D02*
X58900Y-107023D01*
X60646Y-107314D01*
X62174Y-107023D01*
X63485Y-105565D01*
X64358Y-103523D01*
Y-89815D01*
G01Y-92148D02*
X63485Y-90981D01*
X62174Y-90106D01*
X60646Y-89815D01*
X58900Y-90398D01*
X57808Y-91564D01*
X56934Y-93606D01*
X56498Y-95648D01*
X56716Y-97398D01*
X57590Y-99440D01*
X58900Y-100898D01*
X60646Y-101481D01*
X61956Y-101189D01*
X63485Y-100023D01*
X64358Y-98857D01*
G01X74653Y-93606D02*
X81640D01*
X80985Y-91564D01*
X79893Y-90398D01*
X78365Y-89815D01*
X76836Y-90106D01*
X75526Y-90981D01*
X74653Y-93023D01*
X74216Y-94773D01*
Y-96523D01*
X74653Y-98273D01*
X75745Y-100023D01*
X77055Y-101189D01*
X78583Y-101481D01*
X80111Y-100898D01*
X81640Y-99148D01*
G01X92371Y-101481D02*
Y-89815D01*
G01Y-92148D02*
X93463Y-90981D01*
X94555Y-90106D01*
X96083Y-89815D01*
X97174Y-90106D01*
X98485Y-90981D01*
G01X108998Y-101481D02*
Y-83981D01*
G01Y-92731D02*
X110090Y-90981D01*
X111400Y-90106D01*
X112710Y-89815D01*
X114674Y-90398D01*
X115985Y-91564D01*
X116858Y-93606D01*
Y-95939D01*
X116421Y-98273D01*
X115548Y-100023D01*
X114020Y-101189D01*
X112710Y-101481D01*
X111400Y-101189D01*
X110090Y-100315D01*
X108998Y-98857D01*
G01X127153Y-93606D02*
X134140D01*
X133485Y-91564D01*
X132393Y-90398D01*
X130865Y-89815D01*
X129336Y-90106D01*
X128026Y-90981D01*
X127153Y-93023D01*
X126716Y-94773D01*
Y-96523D01*
X127153Y-98273D01*
X128245Y-100023D01*
X129555Y-101189D01*
X131083Y-101481D01*
X132611Y-100898D01*
X134140Y-99148D01*
G01X144871Y-101481D02*
Y-89815D01*
G01Y-92148D02*
X145963Y-90981D01*
X147055Y-90106D01*
X148583Y-89815D01*
X149674Y-90106D01*
X150985Y-90981D01*
G01X182928Y-89815D02*
Y-101481D01*
G01Y-85148D02*
X182491Y-84856D01*
Y-84273D01*
X182928Y-83981D01*
X183365Y-84273D01*
Y-84856D01*
X182928Y-85148D01*
G01X197153Y-99440D02*
X198245Y-100606D01*
X199773Y-101481D01*
X201083D01*
X202393Y-100898D01*
X203266Y-100023D01*
X203703Y-98857D01*
X203485Y-97106D01*
X202611Y-96231D01*
X198681Y-94481D01*
X197808Y-92439D01*
X198245Y-90981D01*
X199118Y-90106D01*
X200428Y-89815D01*
X201738Y-90106D01*
X203048Y-90981D01*
G01X231934Y-105856D02*
X233463Y-107023D01*
X234773Y-107314D01*
X236520Y-106731D01*
X237830Y-105273D01*
X238485Y-102647D01*
Y-89815D01*
G01Y-85148D02*
X238048Y-84856D01*
Y-84273D01*
X238485Y-83981D01*
X238921Y-84273D01*
Y-84856D01*
X238485Y-85148D01*
G01X249216Y-89815D02*
Y-97981D01*
X250090Y-100023D01*
X251400Y-101189D01*
X252928Y-101481D01*
X254456Y-101189D01*
X255766Y-100023D01*
X256640Y-97981D01*
G01Y-101481D02*
Y-89815D01*
G01X267153Y-99440D02*
X268245Y-100606D01*
X269773Y-101481D01*
X271083D01*
X272393Y-100898D01*
X273266Y-100023D01*
X273703Y-98857D01*
X273485Y-97106D01*
X272611Y-96231D01*
X268681Y-94481D01*
X267808Y-92439D01*
X268245Y-90981D01*
X269118Y-90106D01*
X270428Y-89815D01*
X271738Y-90106D01*
X273048Y-90981D01*
G01X287928Y-83981D02*
Y-101481D01*
G01X284871Y-89815D02*
X290985D01*
G01X321618Y-101481D02*
Y-86606D01*
X322055Y-85148D01*
X322928Y-84273D01*
X324238Y-83981D01*
X325548Y-84564D01*
X326203Y-86023D01*
G01X323583Y-90981D02*
X319216D01*
G01X340428Y-101481D02*
X339118Y-101189D01*
X337808Y-100023D01*
X336934Y-97981D01*
X336498Y-95648D01*
X336934Y-93314D01*
X337808Y-91273D01*
X339118Y-90106D01*
X340428Y-89815D01*
X341738Y-90106D01*
X343048Y-91273D01*
X343921Y-93314D01*
X344140Y-95648D01*
X343921Y-97981D01*
X343048Y-100023D01*
X341738Y-101189D01*
X340428Y-101481D01*
G01X354871D02*
Y-89815D01*
G01Y-92148D02*
X355963Y-90981D01*
X357055Y-90106D01*
X358583Y-89815D01*
X359674Y-90106D01*
X360985Y-90981D01*
G01X388343Y-106731D02*
X389653Y-107314D01*
X391400Y-106731D01*
X392491Y-105565D01*
X393365Y-104106D01*
X394674Y-99440D01*
X397513Y-89815D01*
G01X390526D02*
X394674Y-99440D01*
G01X410428Y-101481D02*
X409118Y-101189D01*
X407808Y-100023D01*
X406934Y-97981D01*
X406498Y-95648D01*
X406934Y-93314D01*
X407808Y-91273D01*
X409118Y-90106D01*
X410428Y-89815D01*
X411738Y-90106D01*
X413048Y-91273D01*
X413921Y-93314D01*
X414140Y-95648D01*
X413921Y-97981D01*
X413048Y-100023D01*
X411738Y-101189D01*
X410428Y-101481D01*
G01X424216Y-89815D02*
Y-97981D01*
X425090Y-100023D01*
X426400Y-101189D01*
X427928Y-101481D01*
X429456Y-101189D01*
X430766Y-100023D01*
X431640Y-97981D01*
G01Y-101481D02*
Y-89815D01*
G01X442371Y-101481D02*
Y-89815D01*
G01Y-92148D02*
X443463Y-90981D01*
X444555Y-90106D01*
X446083Y-89815D01*
X447174Y-90106D01*
X448485Y-90981D01*
G01X477371Y-101481D02*
Y-89815D01*
G01Y-92148D02*
X478463Y-90981D01*
X479555Y-90106D01*
X481083Y-89815D01*
X482174Y-90106D01*
X483485Y-90981D01*
G01X494653Y-93606D02*
X501640D01*
X500985Y-91564D01*
X499893Y-90398D01*
X498365Y-89815D01*
X496836Y-90106D01*
X495526Y-90981D01*
X494653Y-93023D01*
X494216Y-94773D01*
Y-96523D01*
X494653Y-98273D01*
X495745Y-100023D01*
X497055Y-101189D01*
X498583Y-101481D01*
X500111Y-100898D01*
X501640Y-99148D01*
G01X514118Y-101481D02*
Y-86606D01*
X514555Y-85148D01*
X515428Y-84273D01*
X516738Y-83981D01*
X518048Y-84564D01*
X518703Y-86023D01*
G01X516083Y-90981D02*
X511716D01*
G01X529653Y-93606D02*
X536640D01*
X535985Y-91564D01*
X534893Y-90398D01*
X533365Y-89815D01*
X531836Y-90106D01*
X530526Y-90981D01*
X529653Y-93023D01*
X529216Y-94773D01*
Y-96523D01*
X529653Y-98273D01*
X530745Y-100023D01*
X532055Y-101189D01*
X533583Y-101481D01*
X535111Y-100898D01*
X536640Y-99148D01*
G01X547371Y-101481D02*
Y-89815D01*
G01Y-92148D02*
X548463Y-90981D01*
X549555Y-90106D01*
X551083Y-89815D01*
X552174Y-90106D01*
X553485Y-90981D01*
G01X564653Y-93606D02*
X571640D01*
X570985Y-91564D01*
X569893Y-90398D01*
X568365Y-89815D01*
X566836Y-90106D01*
X565526Y-90981D01*
X564653Y-93023D01*
X564216Y-94773D01*
Y-96523D01*
X564653Y-98273D01*
X565745Y-100023D01*
X567055Y-101189D01*
X568583Y-101481D01*
X570111Y-100898D01*
X571640Y-99148D01*
G01X581716Y-101481D02*
Y-89815D01*
G01Y-92731D02*
X582590Y-91273D01*
X583900Y-90106D01*
X585646Y-89815D01*
X587174Y-90106D01*
X588485Y-91273D01*
X589140Y-93314D01*
Y-101481D01*
G01X606421Y-91273D02*
X604893Y-90106D01*
X603583Y-89815D01*
X601836Y-90398D01*
X600526Y-91564D01*
X599653Y-93606D01*
X599434Y-95648D01*
X599653Y-97690D01*
X600526Y-99440D01*
X601836Y-100898D01*
X603583Y-101481D01*
X605111Y-100898D01*
X606421Y-99731D01*
G01X617153Y-93606D02*
X624140D01*
X623485Y-91564D01*
X622393Y-90398D01*
X620865Y-89815D01*
X619336Y-90106D01*
X618026Y-90981D01*
X617153Y-93023D01*
X616716Y-94773D01*
Y-96523D01*
X617153Y-98273D01*
X618245Y-100023D01*
X619555Y-101189D01*
X621083Y-101481D01*
X622611Y-100898D01*
X624140Y-99148D01*
G01X655428Y-83981D02*
Y-101481D01*
G01X652371Y-89815D02*
X658485D01*
G01X672928Y-101481D02*
X671618Y-101189D01*
X670308Y-100023D01*
X669434Y-97981D01*
X668998Y-95648D01*
X669434Y-93314D01*
X670308Y-91273D01*
X671618Y-90106D01*
X672928Y-89815D01*
X674238Y-90106D01*
X675548Y-91273D01*
X676421Y-93314D01*
X676640Y-95648D01*
X676421Y-97981D01*
X675548Y-100023D01*
X674238Y-101189D01*
X672928Y-101481D01*
G01X706618D02*
Y-86606D01*
X707055Y-85148D01*
X707928Y-84273D01*
X709238Y-83981D01*
X710548Y-84564D01*
X711203Y-86023D01*
G01X708583Y-90981D02*
X704216D01*
G01X725428Y-89815D02*
Y-101481D01*
G01Y-85148D02*
X724991Y-84856D01*
Y-84273D01*
X725428Y-83981D01*
X725865Y-84273D01*
Y-84856D01*
X725428Y-85148D01*
G01X739216Y-101481D02*
Y-89815D01*
G01Y-92731D02*
X740090Y-91273D01*
X741400Y-90106D01*
X743146Y-89815D01*
X744674Y-90106D01*
X745985Y-91273D01*
X746640Y-93314D01*
Y-101481D01*
G01X764358Y-83981D02*
Y-101481D01*
G01Y-98857D02*
X763485Y-100315D01*
X762174Y-101189D01*
X760646Y-101481D01*
X758900Y-100898D01*
X757590Y-99440D01*
X756716Y-97690D01*
X756498Y-95648D01*
X756716Y-93606D01*
X757590Y-91856D01*
X758900Y-90398D01*
X760646Y-89815D01*
X762174Y-90106D01*
X763266Y-90690D01*
X764358Y-91856D01*
G01X795428Y-83981D02*
Y-101481D01*
G01X792371Y-89815D02*
X798485D01*
G01X809216Y-101481D02*
Y-83981D01*
G01Y-92439D02*
X810308Y-90981D01*
X811400Y-90106D01*
X813146Y-89815D01*
X814456Y-90106D01*
X815985Y-91273D01*
X816640Y-93023D01*
Y-101481D01*
G01X827153Y-93606D02*
X834140D01*
X833485Y-91564D01*
X832393Y-90398D01*
X830865Y-89815D01*
X829336Y-90106D01*
X828026Y-90981D01*
X827153Y-93023D01*
X826716Y-94773D01*
Y-96523D01*
X827153Y-98273D01*
X828245Y-100023D01*
X829555Y-101189D01*
X831083Y-101481D01*
X832611Y-100898D01*
X834140Y-99148D01*
G01X860625Y-101481D02*
Y-83981D01*
X864991D01*
X866738Y-84856D01*
X868048Y-86023D01*
X869140Y-87772D01*
X870013Y-89815D01*
X870231Y-92731D01*
X870013Y-95648D01*
X869140Y-97690D01*
X868048Y-99440D01*
X866738Y-100606D01*
X864991Y-101481D01*
X860625D01*
G01X878561D02*
Y-83981D01*
X883801D01*
X885548Y-84856D01*
X886858Y-86898D01*
X887295Y-89231D01*
X886858Y-91564D01*
X885766Y-93314D01*
X883801Y-94190D01*
X878561D01*
G01X917928Y-89815D02*
Y-101481D01*
G01Y-85148D02*
X917491Y-84856D01*
Y-84273D01*
X917928Y-83981D01*
X918365Y-84273D01*
Y-84856D01*
X917928Y-85148D01*
G01X928878Y-101481D02*
Y-89815D01*
G01Y-93023D02*
X929533Y-91564D01*
X930625Y-90398D01*
X932153Y-89815D01*
X933681Y-90398D01*
X934773Y-91564D01*
X935428Y-93023D01*
Y-101481D01*
G01Y-93023D02*
X936083Y-91564D01*
X937174Y-90398D01*
X938703Y-89815D01*
X940231Y-90398D01*
X941323Y-91564D01*
X941978Y-93314D01*
Y-101481D01*
G01X948998Y-107314D02*
Y-89815D01*
G01Y-92439D02*
X950090Y-90981D01*
X951181Y-90106D01*
X952928Y-89815D01*
X954456Y-90106D01*
X955985Y-91564D01*
X956640Y-93606D01*
X956858Y-95648D01*
X956640Y-97690D01*
X955985Y-99731D01*
X954674Y-100898D01*
X952928Y-101481D01*
X951400Y-101189D01*
X949871Y-100315D01*
X948998Y-99148D01*
G01X967153Y-93606D02*
X974140D01*
X973485Y-91564D01*
X972393Y-90398D01*
X970865Y-89815D01*
X969336Y-90106D01*
X968026Y-90981D01*
X967153Y-93023D01*
X966716Y-94773D01*
Y-96523D01*
X967153Y-98273D01*
X968245Y-100023D01*
X969555Y-101189D01*
X971083Y-101481D01*
X972611Y-100898D01*
X974140Y-99148D01*
G01X991858Y-83981D02*
Y-101481D01*
G01Y-98857D02*
X990985Y-100315D01*
X989674Y-101189D01*
X988146Y-101481D01*
X986400Y-100898D01*
X985090Y-99440D01*
X984216Y-97690D01*
X983998Y-95648D01*
X984216Y-93606D01*
X985090Y-91856D01*
X986400Y-90398D01*
X988146Y-89815D01*
X989674Y-90106D01*
X990766Y-90690D01*
X991858Y-91856D01*
G01X1009358Y-101481D02*
Y-89815D01*
G01Y-91856D02*
X1008485Y-90690D01*
X1007174Y-90106D01*
X1005646Y-89815D01*
X1004118Y-90398D01*
X1002808Y-91564D01*
X1001934Y-93314D01*
X1001498Y-95648D01*
X1001934Y-97981D01*
X1002808Y-99731D01*
X1004118Y-100898D01*
X1005646Y-101481D01*
X1007174Y-101189D01*
X1008485Y-100315D01*
X1009358Y-99148D01*
G01X1019216Y-101481D02*
Y-89815D01*
G01Y-92731D02*
X1020090Y-91273D01*
X1021400Y-90106D01*
X1023146Y-89815D01*
X1024674Y-90106D01*
X1025985Y-91273D01*
X1026640Y-93314D01*
Y-101481D01*
G01X1043921Y-91273D02*
X1042393Y-90106D01*
X1041083Y-89815D01*
X1039336Y-90398D01*
X1038026Y-91564D01*
X1037153Y-93606D01*
X1036934Y-95648D01*
X1037153Y-97690D01*
X1038026Y-99440D01*
X1039336Y-100898D01*
X1041083Y-101481D01*
X1042611Y-100898D01*
X1043921Y-99731D01*
G01X1054653Y-93606D02*
X1061640D01*
X1060985Y-91564D01*
X1059893Y-90398D01*
X1058365Y-89815D01*
X1056836Y-90106D01*
X1055526Y-90981D01*
X1054653Y-93023D01*
X1054216Y-94773D01*
Y-96523D01*
X1054653Y-98273D01*
X1055745Y-100023D01*
X1057055Y-101189D01*
X1058583Y-101481D01*
X1060111Y-100898D01*
X1061640Y-99148D01*
G01X1092928Y-83981D02*
Y-101481D01*
G01X1089871Y-89815D02*
X1095985D01*
G01X1107371Y-101481D02*
Y-89815D01*
G01Y-92148D02*
X1108463Y-90981D01*
X1109555Y-90106D01*
X1111083Y-89815D01*
X1112174Y-90106D01*
X1113485Y-90981D01*
G01X1131858Y-101481D02*
Y-89815D01*
G01Y-91856D02*
X1130985Y-90690D01*
X1129674Y-90106D01*
X1128146Y-89815D01*
X1126618Y-90398D01*
X1125308Y-91564D01*
X1124434Y-93314D01*
X1123998Y-95648D01*
X1124434Y-97981D01*
X1125308Y-99731D01*
X1126618Y-100898D01*
X1128146Y-101481D01*
X1129674Y-101189D01*
X1130985Y-100315D01*
X1131858Y-99148D01*
G01X1148921Y-91273D02*
X1147393Y-90106D01*
X1146083Y-89815D01*
X1144336Y-90398D01*
X1143026Y-91564D01*
X1142153Y-93606D01*
X1141934Y-95648D01*
X1142153Y-97690D01*
X1143026Y-99440D01*
X1144336Y-100898D01*
X1146083Y-101481D01*
X1147611Y-100898D01*
X1148921Y-99731D01*
G01X1159653Y-93606D02*
X1166640D01*
X1165985Y-91564D01*
X1164893Y-90398D01*
X1163365Y-89815D01*
X1161836Y-90106D01*
X1160526Y-90981D01*
X1159653Y-93023D01*
X1159216Y-94773D01*
Y-96523D01*
X1159653Y-98273D01*
X1160745Y-100023D01*
X1162055Y-101189D01*
X1163583Y-101481D01*
X1165111Y-100898D01*
X1166640Y-99148D01*
G01X1177153Y-99440D02*
X1178245Y-100606D01*
X1179773Y-101481D01*
X1181083D01*
X1182393Y-100898D01*
X1183266Y-100023D01*
X1183703Y-98857D01*
X1183485Y-97106D01*
X1182611Y-96231D01*
X1178681Y-94481D01*
X1177808Y-92439D01*
X1178245Y-90981D01*
X1179118Y-90106D01*
X1180428Y-89815D01*
X1181738Y-90106D01*
X1183048Y-90981D01*
G01X1215428Y-89815D02*
Y-101481D01*
G01Y-85148D02*
X1214991Y-84856D01*
Y-84273D01*
X1215428Y-83981D01*
X1215865Y-84273D01*
Y-84856D01*
X1215428Y-85148D01*
G01X1229216Y-101481D02*
Y-89815D01*
G01Y-92731D02*
X1230090Y-91273D01*
X1231400Y-90106D01*
X1233146Y-89815D01*
X1234674Y-90106D01*
X1235985Y-91273D01*
X1236640Y-93314D01*
Y-101481D01*
G01X1267928D02*
Y-83981D01*
G01X1289358Y-101481D02*
Y-89815D01*
G01Y-91856D02*
X1288485Y-90690D01*
X1287174Y-90106D01*
X1285646Y-89815D01*
X1284118Y-90398D01*
X1282808Y-91564D01*
X1281934Y-93314D01*
X1281498Y-95648D01*
X1281934Y-97981D01*
X1282808Y-99731D01*
X1284118Y-100898D01*
X1285646Y-101481D01*
X1287174Y-101189D01*
X1288485Y-100315D01*
X1289358Y-99148D01*
G01X1298343Y-106731D02*
X1299653Y-107314D01*
X1301400Y-106731D01*
X1302491Y-105565D01*
X1303365Y-104106D01*
X1304674Y-99440D01*
X1307513Y-89815D01*
G01X1300526D02*
X1304674Y-99440D01*
G01X1317153Y-93606D02*
X1324140D01*
X1323485Y-91564D01*
X1322393Y-90398D01*
X1320865Y-89815D01*
X1319336Y-90106D01*
X1318026Y-90981D01*
X1317153Y-93023D01*
X1316716Y-94773D01*
Y-96523D01*
X1317153Y-98273D01*
X1318245Y-100023D01*
X1319555Y-101189D01*
X1321083Y-101481D01*
X1322611Y-100898D01*
X1324140Y-99148D01*
G01X1334871Y-101481D02*
Y-89815D01*
G01Y-92148D02*
X1335963Y-90981D01*
X1337055Y-90106D01*
X1338583Y-89815D01*
X1339674Y-90106D01*
X1340985Y-90981D01*
G01X1368561Y-83981D02*
Y-101481D01*
X1377295D01*
G01X1390428D02*
X1391956Y-101189D01*
X1393703Y-100315D01*
X1394795Y-98857D01*
X1395231Y-96814D01*
X1394795Y-94773D01*
X1393485Y-93023D01*
X1391520Y-92148D01*
X1389336D01*
X1388026Y-91564D01*
X1386934Y-90106D01*
X1386498Y-88065D01*
X1387153Y-86023D01*
X1388681Y-84564D01*
X1390428Y-83981D01*
X1392174Y-84564D01*
X1393703Y-86023D01*
X1394358Y-88065D01*
X1393921Y-90106D01*
X1392830Y-91564D01*
X1391520Y-92148D01*
X1389336D01*
X1387371Y-93023D01*
X1386061Y-94773D01*
X1385625Y-96814D01*
X1386061Y-98857D01*
X1387153Y-100315D01*
X1388900Y-101189D01*
X1390428Y-101481D01*
G01X1407928Y-102064D02*
X1407491Y-101773D01*
Y-101189D01*
X1407928Y-100898D01*
X1408365Y-101189D01*
Y-101773D01*
X1407928Y-102064D01*
G01X1481717Y873038D02*
Y890538D01*
X1486083D01*
X1487830Y889663D01*
X1489140Y888496D01*
X1490232Y886747D01*
X1491105Y884704D01*
X1491323Y881788D01*
X1491105Y878871D01*
X1490232Y876829D01*
X1489140Y875079D01*
X1487830Y873913D01*
X1486083Y873038D01*
X1481717D01*
G01X1499653D02*
Y890538D01*
X1504893D01*
X1506640Y889663D01*
X1507950Y887621D01*
X1508387Y885288D01*
X1507950Y882955D01*
X1506858Y881205D01*
X1504893Y880329D01*
X1499653D01*
G01X1536400Y890538D02*
X1541640D01*
G01X1539020D02*
Y873038D01*
G01X1536400D02*
X1541640D01*
G01X1550843D02*
Y890538D01*
X1556520Y875955D01*
X1562197Y890538D01*
Y873038D01*
G01X1569653D02*
Y890538D01*
X1574893D01*
X1576640Y889663D01*
X1577950Y887621D01*
X1578387Y885288D01*
X1577950Y882955D01*
X1576858Y881205D01*
X1574893Y880329D01*
X1569653D01*
G01X1595887Y873038D02*
X1587153D01*
Y890538D01*
X1595887D01*
G01X1592393Y882080D02*
X1587153D01*
G01X1604217Y873038D02*
Y890538D01*
X1608583D01*
X1610330Y889663D01*
X1611640Y888496D01*
X1612732Y886747D01*
X1613605Y884704D01*
X1613823Y881788D01*
X1613605Y878871D01*
X1612732Y876829D01*
X1611640Y875079D01*
X1610330Y873913D01*
X1608583Y873038D01*
X1604217D01*
G01X1621061D02*
X1626520Y890538D01*
X1631979Y873038D01*
G01X1630013Y879163D02*
X1623026D01*
G01X1638998Y873038D02*
Y890538D01*
X1649042Y873038D01*
Y890538D01*
G01X1666323Y889079D02*
X1665013Y889955D01*
X1663485Y890538D01*
X1661738D01*
X1659773Y889663D01*
X1658245Y888205D01*
X1657153Y886454D01*
X1656280Y883538D01*
X1656061Y880913D01*
X1656498Y878288D01*
X1657153Y876538D01*
X1658463Y874788D01*
X1659992Y873621D01*
X1661520Y873038D01*
X1663048D01*
X1664577Y873621D01*
X1665887Y874496D01*
X1666979Y875662D01*
G01X1683387Y873038D02*
X1674653D01*
Y890538D01*
X1683387D01*
G01X1679893Y882080D02*
X1674653D01*
G01X1714020Y890538D02*
Y873038D01*
G01X1708998Y890538D02*
X1719042D01*
G01X1726061Y873038D02*
X1731520Y890538D01*
X1736979Y873038D01*
G01X1735013Y879163D02*
X1728026D01*
G01X1750766Y882371D02*
X1751640Y883246D01*
X1752295Y884704D01*
X1752732Y886747D01*
X1752295Y888496D01*
X1751422Y889663D01*
X1749893Y890538D01*
X1743998D01*
Y873038D01*
X1751203D01*
X1752732Y874204D01*
X1753605Y875955D01*
X1754042Y877996D01*
X1753605Y880038D01*
X1752295Y881788D01*
X1750766Y882371D01*
X1743998D01*
G01X1762153Y890538D02*
Y873038D01*
X1770887D01*
G01X1788387D02*
X1779653D01*
Y890538D01*
X1788387D01*
G01X1784893Y882080D02*
X1779653D01*
G01X1801520Y872455D02*
X1801083Y872746D01*
Y873330D01*
X1801520Y873621D01*
X1801957Y873330D01*
Y872746D01*
X1801520Y872455D01*
G01Y880329D02*
X1801083Y880621D01*
Y881205D01*
X1801520Y881496D01*
X1801957Y881205D01*
Y880621D01*
X1801520Y880329D01*
G01X1832153Y890538D02*
Y873038D01*
X1840887D01*
G01X1854020D02*
X1855548Y873330D01*
X1857295Y874204D01*
X1858387Y875662D01*
X1858823Y877705D01*
X1858387Y879746D01*
X1857077Y881496D01*
X1855112Y882371D01*
X1852928D01*
X1851618Y882955D01*
X1850526Y884413D01*
X1850090Y886454D01*
X1850745Y888496D01*
X1852273Y889955D01*
X1854020Y890538D01*
X1855766Y889955D01*
X1857295Y888496D01*
X1857950Y886454D01*
X1857513Y884413D01*
X1856422Y882955D01*
X1855112Y882371D01*
X1852928D01*
X1850963Y881496D01*
X1849653Y879746D01*
X1849217Y877705D01*
X1849653Y875662D01*
X1850745Y874204D01*
X1852492Y873330D01*
X1854020Y873038D01*
G01X1503600Y855888D02*
X1508840D01*
G01X1506220D02*
Y838388D01*
G01X1503600D02*
X1508840D01*
G01X1518043D02*
Y855888D01*
X1523720Y841305D01*
X1529397Y855888D01*
Y838388D01*
G01X1536853D02*
Y855888D01*
X1542093D01*
X1543840Y855013D01*
X1545150Y852971D01*
X1545587Y850638D01*
X1545150Y848305D01*
X1544058Y846555D01*
X1542093Y845679D01*
X1536853D01*
G01X1557628Y832555D02*
X1555445Y835471D01*
X1554353Y838388D01*
Y850054D01*
X1555445Y852971D01*
X1557628Y855888D01*
G01X1576220Y838388D02*
X1574473Y838680D01*
X1572945Y839846D01*
X1571635Y841596D01*
X1570761Y843638D01*
X1570325Y845971D01*
Y848305D01*
X1570761Y850638D01*
X1571635Y852680D01*
X1572945Y854429D01*
X1574473Y855596D01*
X1576220Y855888D01*
X1577966Y855596D01*
X1579495Y854429D01*
X1580805Y852680D01*
X1581679Y850638D01*
X1582115Y848305D01*
Y845971D01*
X1581679Y843638D01*
X1580805Y841596D01*
X1579495Y839846D01*
X1577966Y838680D01*
X1576220Y838388D01*
G01X1590008D02*
Y855888D01*
G01Y847430D02*
X1591100Y848888D01*
X1592192Y849763D01*
X1593938Y850054D01*
X1595248Y849763D01*
X1596777Y848596D01*
X1597432Y846846D01*
Y838388D01*
G01X1604670D02*
Y850054D01*
G01Y846846D02*
X1605325Y848305D01*
X1606417Y849471D01*
X1607945Y850054D01*
X1609473Y849471D01*
X1610565Y848305D01*
X1611220Y846846D01*
Y838388D01*
G01Y846846D02*
X1611875Y848305D01*
X1612966Y849471D01*
X1614495Y850054D01*
X1616023Y849471D01*
X1617115Y848305D01*
X1617770Y846555D01*
Y838388D01*
G01X1629812Y832555D02*
X1631995Y835471D01*
X1633087Y838388D01*
Y850054D01*
X1631995Y852971D01*
X1629812Y855888D01*
G01X1518917Y768505D02*
X1528523Y781338D01*
G01X1523720Y783671D02*
Y766171D01*
G01X1528523Y768505D02*
X1518917Y781338D01*
G01X1517170Y774921D02*
X1530270D01*
G01X1541220Y769088D02*
Y786588D01*
X1538600Y783088D01*
G01Y769088D02*
X1543840D01*
G01X1558720Y786588D02*
X1556973Y786005D01*
X1555663Y784546D01*
X1554790Y782797D01*
X1554135Y780463D01*
X1553917Y777838D01*
X1554135Y775213D01*
X1554790Y772879D01*
X1555663Y771129D01*
X1556973Y769671D01*
X1558720Y769088D01*
X1560466Y769671D01*
X1561777Y771129D01*
X1562650Y772879D01*
X1563305Y775213D01*
X1563523Y777838D01*
X1563305Y780463D01*
X1562650Y782797D01*
X1561777Y784546D01*
X1560466Y786005D01*
X1558720Y786588D01*
G01X1576220D02*
X1574473Y786005D01*
X1573163Y784546D01*
X1572290Y782797D01*
X1571635Y780463D01*
X1571417Y777838D01*
X1571635Y775213D01*
X1572290Y772879D01*
X1573163Y771129D01*
X1574473Y769671D01*
X1576220Y769088D01*
X1577966Y769671D01*
X1579277Y771129D01*
X1580150Y772879D01*
X1580805Y775213D01*
X1581023Y777838D01*
X1580805Y780463D01*
X1580150Y782797D01*
X1579277Y784546D01*
X1577966Y786005D01*
X1576220Y786588D01*
G01X1593720Y768505D02*
X1593283Y768796D01*
Y769380D01*
X1593720Y769671D01*
X1594157Y769380D01*
Y768796D01*
X1593720Y768505D01*
G01X1611220Y786588D02*
X1609473Y786005D01*
X1608163Y784546D01*
X1607290Y782797D01*
X1606635Y780463D01*
X1606417Y777838D01*
X1606635Y775213D01*
X1607290Y772879D01*
X1608163Y771129D01*
X1609473Y769671D01*
X1611220Y769088D01*
X1612966Y769671D01*
X1614277Y771129D01*
X1615150Y772879D01*
X1615805Y775213D01*
X1616023Y777838D01*
X1615805Y780463D01*
X1615150Y782797D01*
X1614277Y784546D01*
X1612966Y786005D01*
X1611220Y786588D01*
G01X1541220Y803738D02*
X1542748Y804030D01*
X1544495Y804904D01*
X1545587Y806362D01*
X1546023Y808405D01*
X1545587Y810446D01*
X1544277Y812196D01*
X1542312Y813071D01*
X1540128D01*
X1538818Y813655D01*
X1537726Y815113D01*
X1537290Y817154D01*
X1537945Y819196D01*
X1539473Y820655D01*
X1541220Y821238D01*
X1542966Y820655D01*
X1544495Y819196D01*
X1545150Y817154D01*
X1544713Y815113D01*
X1543622Y813655D01*
X1542312Y813071D01*
X1540128D01*
X1538163Y812196D01*
X1536853Y810446D01*
X1536417Y808405D01*
X1536853Y806362D01*
X1537945Y804904D01*
X1539692Y804030D01*
X1541220Y803738D01*
G01X1553917Y806362D02*
X1555226Y804904D01*
X1556755Y804030D01*
X1558720Y803738D01*
X1560685Y804321D01*
X1562213Y805488D01*
X1563305Y807529D01*
X1563523Y809863D01*
X1563087Y812196D01*
X1561995Y813655D01*
X1560466Y814821D01*
X1558938Y815113D01*
X1557410Y814821D01*
X1555445Y813655D01*
X1556100Y821238D01*
X1561995D01*
G01X1576220Y803155D02*
X1575783Y803446D01*
Y804030D01*
X1576220Y804321D01*
X1576657Y804030D01*
Y803446D01*
X1576220Y803155D01*
G01X1593720Y821238D02*
X1591973Y820655D01*
X1590663Y819196D01*
X1589790Y817447D01*
X1589135Y815113D01*
X1588917Y812488D01*
X1589135Y809863D01*
X1589790Y807529D01*
X1590663Y805779D01*
X1591973Y804321D01*
X1593720Y803738D01*
X1595466Y804321D01*
X1596777Y805779D01*
X1597650Y807529D01*
X1598305Y809863D01*
X1598523Y812488D01*
X1598305Y815113D01*
X1597650Y817447D01*
X1596777Y819196D01*
X1595466Y820655D01*
X1593720Y821238D01*
G01X1700920Y855888D02*
X1703976Y838388D01*
X1707470Y855888D01*
X1710963Y838388D01*
X1714020Y855888D01*
G01X1722350D02*
X1727590D01*
G01X1724970D02*
Y838388D01*
G01X1722350D02*
X1727590D01*
G01X1737667D02*
Y855888D01*
X1742033D01*
X1743780Y855013D01*
X1745090Y853846D01*
X1746182Y852097D01*
X1747055Y850054D01*
X1747273Y847138D01*
X1747055Y844221D01*
X1746182Y842179D01*
X1745090Y840429D01*
X1743780Y839263D01*
X1742033Y838388D01*
X1737667D01*
G01X1759970Y855888D02*
Y838388D01*
G01X1754948Y855888D02*
X1764992D01*
G01X1772885Y838388D02*
Y855888D01*
G01X1782055D02*
Y838388D01*
G01Y847138D02*
X1772885D01*
G01X1793878Y832555D02*
X1791695Y835471D01*
X1790603Y838388D01*
Y850054D01*
X1791695Y852971D01*
X1793878Y855888D01*
G01X1805920Y838388D02*
Y850054D01*
G01Y846846D02*
X1806575Y848305D01*
X1807667Y849471D01*
X1809195Y850054D01*
X1810723Y849471D01*
X1811815Y848305D01*
X1812470Y846846D01*
Y838388D01*
G01Y846846D02*
X1813125Y848305D01*
X1814216Y849471D01*
X1815745Y850054D01*
X1817273Y849471D01*
X1818365Y848305D01*
X1819020Y846555D01*
Y838388D01*
G01X1829970Y850054D02*
Y838388D01*
G01Y854721D02*
X1829533Y855013D01*
Y855596D01*
X1829970Y855888D01*
X1830407Y855596D01*
Y855013D01*
X1829970Y854721D01*
G01X1847470Y838388D02*
Y855888D01*
G01X1861695Y840429D02*
X1862787Y839263D01*
X1864315Y838388D01*
X1865625D01*
X1866935Y838971D01*
X1867808Y839846D01*
X1868245Y841012D01*
X1868027Y842763D01*
X1867153Y843638D01*
X1863223Y845388D01*
X1862350Y847430D01*
X1862787Y848888D01*
X1863660Y849763D01*
X1864970Y850054D01*
X1866280Y849763D01*
X1867590Y848888D01*
G01X1883562Y832555D02*
X1885745Y835471D01*
X1886837Y838388D01*
Y850054D01*
X1885745Y852971D01*
X1883562Y855888D01*
G01X1727590Y769088D02*
Y786588D01*
X1719511Y774046D01*
X1730429D01*
G01X1742470Y768505D02*
X1742033Y768796D01*
Y769380D01*
X1742470Y769671D01*
X1742907Y769380D01*
Y768796D01*
X1742470Y768505D01*
G01X1759970Y769088D02*
Y786588D01*
X1757350Y783088D01*
G01Y769088D02*
X1762590D01*
G01X1772667Y772588D02*
X1773976Y770546D01*
X1775723Y769380D01*
X1777688Y769088D01*
X1779435Y769380D01*
X1781182Y770838D01*
X1782273Y772588D01*
X1782492Y774338D01*
X1782055Y776379D01*
X1780527Y777838D01*
X1778998Y778421D01*
X1777033D01*
G01X1778998D02*
X1780308Y779296D01*
X1781400Y780754D01*
X1781837Y782504D01*
X1781400Y784255D01*
X1780308Y785713D01*
X1778343Y786588D01*
X1776378Y786296D01*
X1774413Y785129D01*
G01X1791040Y768505D02*
X1798900Y786588D01*
G01X1808758Y771129D02*
X1810287Y769671D01*
X1812033Y769088D01*
X1813780Y769671D01*
X1815308Y771421D01*
X1816400Y774046D01*
X1816837Y776671D01*
Y779879D01*
X1816400Y782504D01*
X1815308Y784838D01*
X1813998Y786005D01*
X1812470Y786588D01*
X1810723Y786005D01*
X1809413Y784838D01*
X1808540Y783088D01*
X1808103Y780754D01*
X1808540Y778713D01*
X1809632Y776671D01*
X1810942Y775504D01*
X1812470Y775213D01*
X1814216Y775796D01*
X1815527Y777255D01*
X1816837Y779879D01*
G01X1829970Y768505D02*
X1829533Y768796D01*
Y769380D01*
X1829970Y769671D01*
X1830407Y769380D01*
Y768796D01*
X1829970Y768505D01*
G01X1842667Y772588D02*
X1843976Y770546D01*
X1845723Y769380D01*
X1847688Y769088D01*
X1849435Y769380D01*
X1851182Y770838D01*
X1852273Y772588D01*
X1852492Y774338D01*
X1852055Y776379D01*
X1850527Y777838D01*
X1848998Y778421D01*
X1847033D01*
G01X1848998D02*
X1850308Y779296D01*
X1851400Y780754D01*
X1851837Y782504D01*
X1851400Y784255D01*
X1850308Y785713D01*
X1848343Y786588D01*
X1846378Y786296D01*
X1844413Y785129D01*
G01X1864533Y769088D02*
X1864970Y772879D01*
X1865625Y776088D01*
X1866498Y779005D01*
X1867590Y782213D01*
X1869337Y786588D01*
X1860603D01*
G01X1720167Y806362D02*
X1721476Y804904D01*
X1723005Y804030D01*
X1724970Y803738D01*
X1726935Y804321D01*
X1728463Y805488D01*
X1729555Y807529D01*
X1729773Y809863D01*
X1729337Y812196D01*
X1728245Y813655D01*
X1726716Y814821D01*
X1725188Y815113D01*
X1723660Y814821D01*
X1721695Y813655D01*
X1722350Y821238D01*
X1728245D01*
G01X1742470Y803155D02*
X1742033Y803446D01*
Y804030D01*
X1742470Y804321D01*
X1742907Y804030D01*
Y803446D01*
X1742470Y803155D01*
G01X1755167Y807238D02*
X1756476Y805196D01*
X1758223Y804030D01*
X1760188Y803738D01*
X1761935Y804030D01*
X1763682Y805488D01*
X1764773Y807238D01*
X1764992Y808988D01*
X1764555Y811029D01*
X1763027Y812488D01*
X1761498Y813071D01*
X1759533D01*
G01X1761498D02*
X1762808Y813946D01*
X1763900Y815404D01*
X1764337Y817154D01*
X1763900Y818905D01*
X1762808Y820363D01*
X1760843Y821238D01*
X1758878Y820946D01*
X1756913Y819779D01*
G01X1777470Y803738D02*
X1778998Y804030D01*
X1780745Y804904D01*
X1781837Y806362D01*
X1782273Y808405D01*
X1781837Y810446D01*
X1780527Y812196D01*
X1778562Y813071D01*
X1776378D01*
X1775068Y813655D01*
X1773976Y815113D01*
X1773540Y817154D01*
X1774195Y819196D01*
X1775723Y820655D01*
X1777470Y821238D01*
X1779216Y820655D01*
X1780745Y819196D01*
X1781400Y817154D01*
X1780963Y815113D01*
X1779872Y813655D01*
X1778562Y813071D01*
X1776378D01*
X1774413Y812196D01*
X1773103Y810446D01*
X1772667Y808405D01*
X1773103Y806362D01*
X1774195Y804904D01*
X1775942Y804030D01*
X1777470Y803738D01*
G01X1791040Y803155D02*
X1798900Y821238D01*
G01X1808322Y811029D02*
X1809850Y813071D01*
X1811160Y814238D01*
X1812907Y814821D01*
X1814435Y814238D01*
X1815527Y813071D01*
X1816400Y811321D01*
X1816618Y809280D01*
X1816400Y807529D01*
X1815527Y805779D01*
X1814216Y804321D01*
X1812688Y803738D01*
X1810942Y804321D01*
X1809413Y806071D01*
X1808540Y808696D01*
X1808322Y811613D01*
X1808758Y815404D01*
X1809413Y817447D01*
X1810505Y819488D01*
X1812033Y820946D01*
X1813562Y821238D01*
X1815090Y820655D01*
X1816182Y819196D01*
G01X1829970Y803155D02*
X1829533Y803446D01*
Y804030D01*
X1829970Y804321D01*
X1830407Y804030D01*
Y803446D01*
X1829970Y803155D01*
G01X1843322Y811029D02*
X1844850Y813071D01*
X1846160Y814238D01*
X1847907Y814821D01*
X1849435Y814238D01*
X1850527Y813071D01*
X1851400Y811321D01*
X1851618Y809280D01*
X1851400Y807529D01*
X1850527Y805779D01*
X1849216Y804321D01*
X1847688Y803738D01*
X1845942Y804321D01*
X1844413Y806071D01*
X1843540Y808696D01*
X1843322Y811613D01*
X1843758Y815404D01*
X1844413Y817447D01*
X1845505Y819488D01*
X1847033Y820946D01*
X1848562Y821238D01*
X1850090Y820655D01*
X1851182Y819196D01*
G01X1860822Y818321D02*
X1862132Y820071D01*
X1863660Y820946D01*
X1865407Y821238D01*
X1867590Y820655D01*
X1869118Y819196D01*
X1869555Y817447D01*
X1869337Y815696D01*
X1868463Y814238D01*
X1864097Y811321D01*
X1862132Y809280D01*
X1860822Y806362D01*
X1860385Y803738D01*
X1869555D01*
G01X1973917Y769088D02*
Y786588D01*
X1978283D01*
X1980030Y785713D01*
X1981340Y784546D01*
X1982432Y782797D01*
X1983305Y780754D01*
X1983523Y777838D01*
X1983305Y774921D01*
X1982432Y772879D01*
X1981340Y771129D01*
X1980030Y769963D01*
X1978283Y769088D01*
X1973917D01*
G01X1991853D02*
Y786588D01*
X1997093D01*
X1998840Y785713D01*
X2000150Y783671D01*
X2000587Y781338D01*
X2000150Y779005D01*
X1999058Y777255D01*
X1997093Y776379D01*
X1991853D01*
G01X1973917Y803738D02*
Y821238D01*
X1978283D01*
X1980030Y820363D01*
X1981340Y819196D01*
X1982432Y817447D01*
X1983305Y815404D01*
X1983523Y812488D01*
X1983305Y809571D01*
X1982432Y807529D01*
X1981340Y805779D01*
X1980030Y804613D01*
X1978283Y803738D01*
X1973917D01*
G01X1991853D02*
Y821238D01*
X1997093D01*
X1998840Y820363D01*
X2000150Y818321D01*
X2000587Y815988D01*
X2000150Y813655D01*
X1999058Y811905D01*
X1997093Y811029D01*
X1991853D01*
G01X1961220Y855888D02*
Y838388D01*
G01X1956198Y855888D02*
X1966242D01*
G01X1978720Y838388D02*
Y846263D01*
X1974353Y855888D01*
G01X1983087D02*
X1978720Y846263D01*
G01X1991853Y838388D02*
Y855888D01*
X1997093D01*
X1998840Y855013D01*
X2000150Y852971D01*
X2000587Y850638D01*
X2000150Y848305D01*
X1999058Y846555D01*
X1997093Y845679D01*
X1991853D01*
G01X2018087Y838388D02*
X2009353D01*
Y855888D01*
X2018087D01*
G01X2014593Y847430D02*
X2009353D01*
G01X2061853Y838388D02*
Y855888D01*
X2067312D01*
X2069058Y855013D01*
X2070150Y853846D01*
X2070587Y851513D01*
X2070150Y849179D01*
X2068840Y847721D01*
X2067312Y846846D01*
X2061853D01*
G01X2067312D02*
X2070587Y838388D01*
G01X2080445Y846263D02*
X2087432D01*
X2086777Y848305D01*
X2085685Y849471D01*
X2084157Y850054D01*
X2082628Y849763D01*
X2081318Y848888D01*
X2080445Y846846D01*
X2080008Y845096D01*
Y843346D01*
X2080445Y841596D01*
X2081537Y839846D01*
X2082847Y838680D01*
X2084375Y838388D01*
X2085903Y838971D01*
X2087432Y840721D01*
G01X2099910Y838388D02*
Y853263D01*
X2100347Y854721D01*
X2101220Y855596D01*
X2102530Y855888D01*
X2103840Y855305D01*
X2104495Y853846D01*
G01X2101875Y848888D02*
X2097508D01*
G01X2118720Y837805D02*
X2118283Y838096D01*
Y838680D01*
X2118720Y838971D01*
X2119157Y838680D01*
Y838096D01*
X2118720Y837805D01*
G01X2149353Y838388D02*
Y855888D01*
X2154593D01*
X2156340Y855013D01*
X2157650Y852971D01*
X2158087Y850638D01*
X2157650Y848305D01*
X2156558Y846555D01*
X2154593Y845679D01*
X2149353D01*
G01X2171220Y838388D02*
Y855888D01*
G01X2192650Y838388D02*
Y850054D01*
G01Y848013D02*
X2191777Y849179D01*
X2190466Y849763D01*
X2188938Y850054D01*
X2187410Y849471D01*
X2186100Y848305D01*
X2185226Y846555D01*
X2184790Y844221D01*
X2185226Y841888D01*
X2186100Y840138D01*
X2187410Y838971D01*
X2188938Y838388D01*
X2190466Y838680D01*
X2191777Y839554D01*
X2192650Y840721D01*
G01X2202508Y838388D02*
Y850054D01*
G01Y847138D02*
X2203382Y848596D01*
X2204692Y849763D01*
X2206438Y850054D01*
X2207966Y849763D01*
X2209277Y848596D01*
X2209932Y846555D01*
Y838388D01*
G01X2220445Y846263D02*
X2227432D01*
X2226777Y848305D01*
X2225685Y849471D01*
X2224157Y850054D01*
X2222628Y849763D01*
X2221318Y848888D01*
X2220445Y846846D01*
X2220008Y845096D01*
Y843346D01*
X2220445Y841596D01*
X2221537Y839846D01*
X2222847Y838680D01*
X2224375Y838388D01*
X2225903Y838971D01*
X2227432Y840721D01*
G01X2131853Y786588D02*
Y769088D01*
X2140587D01*
G01X2153283D02*
X2153720Y772879D01*
X2154375Y776088D01*
X2155248Y779005D01*
X2156340Y782213D01*
X2158087Y786588D01*
X2149353D01*
G01X2131853Y821238D02*
Y803738D01*
X2140587D01*
G01X2153283D02*
X2153720Y807529D01*
X2154375Y810738D01*
X2155248Y813655D01*
X2156340Y816863D01*
X2158087Y821238D01*
X2149353D01*
G01X2341520Y815404D02*
Y803738D01*
G01Y820071D02*
X2341083Y820363D01*
Y820946D01*
X2341520Y821238D01*
X2341957Y820946D01*
Y820363D01*
X2341520Y820071D01*
G01X2355745Y805779D02*
X2356837Y804613D01*
X2358365Y803738D01*
X2359675D01*
X2360985Y804321D01*
X2361858Y805196D01*
X2362295Y806362D01*
X2362077Y808113D01*
X2361203Y808988D01*
X2357273Y810738D01*
X2356400Y812780D01*
X2356837Y814238D01*
X2357710Y815113D01*
X2359020Y815404D01*
X2360330Y815113D01*
X2361640Y814238D01*
G01X2388998Y803738D02*
Y821238D01*
X2399042Y803738D01*
Y821238D01*
G01X2411520Y803738D02*
X2409773Y804030D01*
X2408245Y805196D01*
X2406935Y806946D01*
X2406061Y808988D01*
X2405625Y811321D01*
Y813655D01*
X2406061Y815988D01*
X2406935Y818030D01*
X2408245Y819779D01*
X2409773Y820946D01*
X2411520Y821238D01*
X2413266Y820946D01*
X2414795Y819779D01*
X2416105Y818030D01*
X2416979Y815988D01*
X2417415Y813655D01*
Y811321D01*
X2416979Y808988D01*
X2416105Y806946D01*
X2414795Y805196D01*
X2413266Y804030D01*
X2411520Y803738D01*
G01X2429020Y821238D02*
Y803738D01*
G01X2423998Y821238D02*
X2434042D01*
G01X2460308Y815404D02*
Y807238D01*
X2461182Y805196D01*
X2462492Y804030D01*
X2464020Y803738D01*
X2465548Y804030D01*
X2466858Y805196D01*
X2467732Y807238D01*
G01Y803738D02*
Y815404D01*
G01X2478245Y805779D02*
X2479337Y804613D01*
X2480865Y803738D01*
X2482175D01*
X2483485Y804321D01*
X2484358Y805196D01*
X2484795Y806362D01*
X2484577Y808113D01*
X2483703Y808988D01*
X2479773Y810738D01*
X2478900Y812780D01*
X2479337Y814238D01*
X2480210Y815113D01*
X2481520Y815404D01*
X2482830Y815113D01*
X2484140Y814238D01*
G01X2495745Y811613D02*
X2502732D01*
X2502077Y813655D01*
X2500985Y814821D01*
X2499457Y815404D01*
X2497928Y815113D01*
X2496618Y814238D01*
X2495745Y812196D01*
X2495308Y810446D01*
Y808696D01*
X2495745Y806946D01*
X2496837Y805196D01*
X2498147Y804030D01*
X2499675Y803738D01*
X2501203Y804321D01*
X2502732Y806071D01*
G01X2520450Y821238D02*
Y803738D01*
G01Y806362D02*
X2519577Y804904D01*
X2518266Y804030D01*
X2516738Y803738D01*
X2514992Y804321D01*
X2513682Y805779D01*
X2512808Y807529D01*
X2512590Y809571D01*
X2512808Y811613D01*
X2513682Y813363D01*
X2514992Y814821D01*
X2516738Y815404D01*
X2518266Y815113D01*
X2519358Y814529D01*
X2520450Y813363D01*
G01X2266717Y837805D02*
X2276323Y850638D01*
G01X2271520Y852971D02*
Y835471D01*
G01X2276323Y837805D02*
X2266717Y850638D01*
G01X2264970Y844221D02*
X2278070D01*
G01X2303682D02*
X2309358D01*
G01X2336717Y838388D02*
Y855888D01*
X2341083D01*
X2342830Y855013D01*
X2344140Y853846D01*
X2345232Y852097D01*
X2346105Y850054D01*
X2346323Y847138D01*
X2346105Y844221D01*
X2345232Y842179D01*
X2344140Y840429D01*
X2342830Y839263D01*
X2341083Y838388D01*
X2336717D01*
G01X2355745Y846263D02*
X2362732D01*
X2362077Y848305D01*
X2360985Y849471D01*
X2359457Y850054D01*
X2357928Y849763D01*
X2356618Y848888D01*
X2355745Y846846D01*
X2355308Y845096D01*
Y843346D01*
X2355745Y841596D01*
X2356837Y839846D01*
X2358147Y838680D01*
X2359675Y838388D01*
X2361203Y838971D01*
X2362732Y840721D01*
G01X2372808Y838388D02*
Y850054D01*
G01Y847138D02*
X2373682Y848596D01*
X2374992Y849763D01*
X2376738Y850054D01*
X2378266Y849763D01*
X2379577Y848596D01*
X2380232Y846555D01*
Y838388D01*
G01X2394020D02*
X2392710Y838680D01*
X2391400Y839846D01*
X2390526Y841888D01*
X2390090Y844221D01*
X2390526Y846555D01*
X2391400Y848596D01*
X2392710Y849763D01*
X2394020Y850054D01*
X2395330Y849763D01*
X2396640Y848596D01*
X2397513Y846555D01*
X2397732Y844221D01*
X2397513Y841888D01*
X2396640Y839846D01*
X2395330Y838680D01*
X2394020Y838388D01*
G01X2411520Y855888D02*
Y838388D01*
G01X2408463Y850054D02*
X2414577D01*
G01X2425745Y846263D02*
X2432732D01*
X2432077Y848305D01*
X2430985Y849471D01*
X2429457Y850054D01*
X2427928Y849763D01*
X2426618Y848888D01*
X2425745Y846846D01*
X2425308Y845096D01*
Y843346D01*
X2425745Y841596D01*
X2426837Y839846D01*
X2428147Y838680D01*
X2429675Y838388D01*
X2431203Y838971D01*
X2432732Y840721D01*
G01X2443245Y840429D02*
X2444337Y839263D01*
X2445865Y838388D01*
X2447175D01*
X2448485Y838971D01*
X2449358Y839846D01*
X2449795Y841012D01*
X2449577Y842763D01*
X2448703Y843638D01*
X2444773Y845388D01*
X2443900Y847430D01*
X2444337Y848888D01*
X2445210Y849763D01*
X2446520Y850054D01*
X2447830Y849763D01*
X2449140Y848888D01*
G01X2481520Y855888D02*
Y838388D01*
G01X2478463Y850054D02*
X2484577D01*
G01X2495308Y838388D02*
Y855888D01*
G01Y847430D02*
X2496400Y848888D01*
X2497492Y849763D01*
X2499238Y850054D01*
X2500548Y849763D01*
X2502077Y848596D01*
X2502732Y846846D01*
Y838388D01*
G01X2520450D02*
Y850054D01*
G01Y848013D02*
X2519577Y849179D01*
X2518266Y849763D01*
X2516738Y850054D01*
X2515210Y849471D01*
X2513900Y848305D01*
X2513026Y846555D01*
X2512590Y844221D01*
X2513026Y841888D01*
X2513900Y840138D01*
X2515210Y838971D01*
X2516738Y838388D01*
X2518266Y838680D01*
X2519577Y839554D01*
X2520450Y840721D01*
G01X2534020Y855888D02*
Y838388D01*
G01X2530963Y850054D02*
X2537077D01*
G01X2569020Y855888D02*
Y838388D01*
G01X2565963Y850054D02*
X2572077D01*
G01X2582808Y838388D02*
Y855888D01*
G01Y847430D02*
X2583900Y848888D01*
X2584992Y849763D01*
X2586738Y850054D01*
X2588048Y849763D01*
X2589577Y848596D01*
X2590232Y846846D01*
Y838388D01*
G01X2604020Y850054D02*
Y838388D01*
G01Y854721D02*
X2603583Y855013D01*
Y855596D01*
X2604020Y855888D01*
X2604457Y855596D01*
Y855013D01*
X2604020Y854721D01*
G01X2618245Y840429D02*
X2619337Y839263D01*
X2620865Y838388D01*
X2622175D01*
X2623485Y838971D01*
X2624358Y839846D01*
X2624795Y841012D01*
X2624577Y842763D01*
X2623703Y843638D01*
X2619773Y845388D01*
X2618900Y847430D01*
X2619337Y848888D01*
X2620210Y849763D01*
X2621520Y850054D01*
X2622830Y849763D01*
X2624140Y848888D01*
G01X2653900Y855888D02*
X2659140D01*
G01X2656520D02*
Y838388D01*
G01X2653900D02*
X2659140D01*
G01X2667470D02*
Y850054D01*
G01Y846846D02*
X2668125Y848305D01*
X2669217Y849471D01*
X2670745Y850054D01*
X2672273Y849471D01*
X2673365Y848305D01*
X2674020Y846846D01*
Y838388D01*
G01Y846846D02*
X2674675Y848305D01*
X2675766Y849471D01*
X2677295Y850054D01*
X2678823Y849471D01*
X2679915Y848305D01*
X2680570Y846555D01*
Y838388D01*
G01X2687590Y832555D02*
Y850054D01*
G01Y847430D02*
X2688682Y848888D01*
X2689773Y849763D01*
X2691520Y850054D01*
X2693048Y849763D01*
X2694577Y848305D01*
X2695232Y846263D01*
X2695450Y844221D01*
X2695232Y842179D01*
X2694577Y840138D01*
X2693266Y838971D01*
X2691520Y838388D01*
X2689992Y838680D01*
X2688463Y839554D01*
X2687590Y840721D01*
G01X2705745Y846263D02*
X2712732D01*
X2712077Y848305D01*
X2710985Y849471D01*
X2709457Y850054D01*
X2707928Y849763D01*
X2706618Y848888D01*
X2705745Y846846D01*
X2705308Y845096D01*
Y843346D01*
X2705745Y841596D01*
X2706837Y839846D01*
X2708147Y838680D01*
X2709675Y838388D01*
X2711203Y838971D01*
X2712732Y840721D01*
G01X2730450Y855888D02*
Y838388D01*
G01Y841012D02*
X2729577Y839554D01*
X2728266Y838680D01*
X2726738Y838388D01*
X2724992Y838971D01*
X2723682Y840429D01*
X2722808Y842179D01*
X2722590Y844221D01*
X2722808Y846263D01*
X2723682Y848013D01*
X2724992Y849471D01*
X2726738Y850054D01*
X2728266Y849763D01*
X2729358Y849179D01*
X2730450Y848013D01*
G01X2747950Y838388D02*
Y850054D01*
G01Y848013D02*
X2747077Y849179D01*
X2745766Y849763D01*
X2744238Y850054D01*
X2742710Y849471D01*
X2741400Y848305D01*
X2740526Y846555D01*
X2740090Y844221D01*
X2740526Y841888D01*
X2741400Y840138D01*
X2742710Y838971D01*
X2744238Y838388D01*
X2745766Y838680D01*
X2747077Y839554D01*
X2747950Y840721D01*
G01X2757808Y838388D02*
Y850054D01*
G01Y847138D02*
X2758682Y848596D01*
X2759992Y849763D01*
X2761738Y850054D01*
X2763266Y849763D01*
X2764577Y848596D01*
X2765232Y846555D01*
Y838388D01*
G01X2782513Y848596D02*
X2780985Y849763D01*
X2779675Y850054D01*
X2777928Y849471D01*
X2776618Y848305D01*
X2775745Y846263D01*
X2775526Y844221D01*
X2775745Y842179D01*
X2776618Y840429D01*
X2777928Y838971D01*
X2779675Y838388D01*
X2781203Y838971D01*
X2782513Y840138D01*
G01X2793245Y846263D02*
X2800232D01*
X2799577Y848305D01*
X2798485Y849471D01*
X2796957Y850054D01*
X2795428Y849763D01*
X2794118Y848888D01*
X2793245Y846846D01*
X2792808Y845096D01*
Y843346D01*
X2793245Y841596D01*
X2794337Y839846D01*
X2795647Y838680D01*
X2797175Y838388D01*
X2798703Y838971D01*
X2800232Y840721D01*
G01X1425733Y-51181D02*
X-29385D01*
G01X-33322Y-47244D02*
G03X-29385Y-51181I3937J0D01*
G01X-33322Y-47244D02*
Y893701D01*
G01X-7874Y102402D02*
Y212205D01*
G01Y102402D02*
G03X0Y94528I7874J0D01*
G01Y212205D02*
G03X-7874I-3937J0D01*
G01Y237402D02*
G03X0I3937J-1D01*
G01X-7874D02*
Y406693D01*
G01X0D02*
G03X-7874I-3937J0D01*
G01Y431890D02*
G03X0I3937J0D01*
G01X-7874D02*
Y601181D01*
G01X0D02*
G03X-7874I-3937J0D01*
G01Y626378D02*
Y795669D01*
G01Y626378D02*
G03X0I3937J0D01*
G01Y795669D02*
G03X-7874I-3937J0D01*
G01Y820866D02*
G03X0I3937J0D01*
G01X-7874Y844488D02*
Y820866D01*
G01X-3937Y848425D02*
G03X-7874Y844488I0J-3937D01*
G01X93307Y848425D02*
X-3937D01*
G01X-29385Y897638D02*
G03X-33322Y893701I0J-3937D01*
G01X-29385Y897638D02*
X93307D01*
G01X98425Y94528D02*
X0D01*
G01X1400000Y36220D02*
G03X1398031Y38189I-1969J0D01*
G01X1396654D01*
G02X1394685Y40157I0J1969D01*
G01Y71654D01*
G02X1396654Y73622I1969J-1D01*
G01X1398031D01*
G03X1400000Y75591I0J1969D01*
G01Y836614D01*
G03X1396063Y840551I-3937J0D01*
G01X1368504D01*
G02X1363386Y845669I0J5118D01*
G01Y871654D01*
G03X1361417Y873622I-1969J-1D01*
G01X1358268D01*
G02X1356299Y875591I0J1969D01*
G01Y892521D01*
X1352363Y897638D01*
X1218110D01*
X1214173Y892520D01*
Y875984D01*
G02X1205512I-4331J0D01*
G01Y892520D01*
X1201575Y897638D01*
X1029528D01*
X1025591Y892520D01*
Y875591D01*
G02X1023622Y873622I-1969J0D01*
G01X1020472D01*
G03X1018504Y871654I0J-1968D01*
G01Y845669D01*
G02X1013386Y840551I-5118J0D01*
G01X1008433D01*
G03X988748Y820866I0J-19685D01*
G01Y650669D01*
G02X983748Y645669I-5000J0D01*
G01X926819D01*
G02X921819Y650669I0J5000D01*
G01Y820866D01*
G03X902134Y840551I-19685J0D01*
G01X872441D01*
G02X867323Y845669I0J5118D01*
G01Y871654D01*
G03X865354Y873622I-1969J-1D01*
G01X862205D01*
G02X860236Y875591I0J1969D01*
G01Y892521D01*
X856300Y897638D01*
X722048D01*
X718110Y892519D01*
Y875984D01*
G02X709449I-4331J0D01*
G01Y892520D01*
X705512Y897638D01*
X533465D01*
X529528Y892520D01*
Y875591D01*
G02X527559Y873622I-1969J0D01*
G01X524409D01*
G03X522441Y871654I0J-1968D01*
G01Y845669D01*
G02X517323Y840551I-5118J0D01*
G01X455118D01*
G02X450000Y845669I0J5118D01*
G01Y871654D01*
G03X448031Y873622I-1968J0D01*
G01X444882D01*
G02X442913Y875591I0J1969D01*
G01Y892521D01*
X438977Y897638D01*
X304725D01*
X300787Y892519D01*
Y875984D01*
G02X292126I-4331J0D01*
G01Y892521D01*
X288190Y897638D01*
X116142D01*
X112205Y892520D01*
Y875591D01*
G02X110236Y873622I-1969J0D01*
G01X107087D01*
G03X105118Y871654I0J-1969D01*
G01Y845669D01*
G02X100000Y840551I-5118J0D01*
G01X3937D01*
G03X0Y836614I0J-3937D01*
G01Y110276D01*
G03X7874Y102402I7874J0D01*
G01X196654D01*
G02X204528Y94528I0J-7874D01*
G01Y7874D01*
G03X212402Y0I7874J0D01*
G01X471014D01*
G02X478888Y-7874I0J-7874D01*
G01Y-11811D01*
G03X486762Y-19685I7874J0D01*
G01X1302165D01*
G03X1306102Y-15748I0J3937D01*
G01Y-3937D01*
G02X1310039Y0I3937J0D01*
G01X1396063D01*
G03X1400000Y3937I0J3937D01*
G01Y36220D01*
G01X93307Y848425D02*
G03X97244Y852362I0J3937D01*
G01Y893701D02*
Y852362D01*
G01Y893701D02*
G03X93307Y897638I-3937J0D01*
G01X192717Y94528D02*
X123622D01*
G01Y102402D02*
G03Y94528I0J-3937D01*
G01X98425D02*
G03Y102402I0J3937D01*
G01X196654Y0D02*
G03X204528Y-7874I7874J0D01*
G01X196654Y0D02*
Y29961D01*
G01X204528D02*
G03X196654I-3937J0D01*
G01Y55157D02*
Y90591D01*
G01Y55157D02*
G03X204528I3937J0D01*
G01X196654Y90591D02*
G03X192717Y94528I-3937J0D01*
G01X232077Y-7874D02*
G03Y0I0J3937D01*
G01Y-7874D02*
X204528D01*
G01X434439D02*
X257274D01*
G01Y0D02*
G03Y-7874I0J-3937D01*
G01X365945Y38188D02*
G03X367914Y40156I0J1969D01*
G01X354134D02*
G03X356103Y38188I1969J1D01*
G01D02*
X365945D01*
G01X354134Y71653D02*
Y40156D01*
G01X367914Y71653D02*
G03X365945Y73621I-1969J-1D01*
G01X356103D02*
G03X354134Y71653I0J-1969D01*
G01X365945Y73621D02*
X356103D01*
G01X367914Y40156D02*
Y71653D01*
G01X434439Y-7874D02*
G03Y0I0J3937D01*
G01X471014Y-15748D02*
G03X463140Y-7874I-7874J0D01*
G01D02*
X459636D01*
G01Y0D02*
G03Y-7874I0J-3937D01*
G01X707234Y-27559D02*
X478888D01*
G01X471014Y-19685D02*
G03X478888Y-27559I7874J0D01*
G01X471014Y-19685D02*
Y-15748D01*
G01X870226Y-27559D02*
X732431D01*
G01Y-19685D02*
G03Y-27559I0J-3937D01*
G01X707234D02*
G03Y-19685I0J3937D01*
G01X870226Y-27559D02*
G03Y-19685I1J3937D01*
G01X1072589Y-27559D02*
X895423D01*
G01Y-19685D02*
G03Y-27559I0J-3937D01*
G01X1072589D02*
G03Y-19685I0J3937D01*
G01X1097785D02*
G03Y-27559I1J-3937D01*
G01X1336086Y-8662D02*
X1318701D01*
G03X1314764Y-12599I0J-3937D01*
G01Y-23622D01*
G02X1310827Y-27559I-3937J0D01*
G01X1097785D01*
G01X1336086Y-8662D02*
G03Y-1I0J4330D01*
G01X1361283D02*
G03Y-8662I0J-4330D01*
G01X1407874Y13026D02*
Y-4725D01*
G02X1403937Y-8662I-3937J0D01*
G01X1361283D01*
G01X1403937Y848425D02*
X1375197D01*
G01X1371260Y852362D02*
G03X1375197Y848425I3937J0D01*
G01X1371260Y852362D02*
Y893701D01*
G01X1375197Y897638D02*
G03X1371260Y893701I0J-3937D01*
G01X1375197Y897638D02*
X1425733D01*
G01X1407874Y30709D02*
Y219685D01*
G01X1400000Y30709D02*
G03X1407874I3937J0D01*
G01Y13026D02*
G03X1400000I-3937J-1D01*
G01X1407874Y219685D02*
G03X1400000I-3937J0D01*
G01Y244882D02*
G03X1407874I3937J0D01*
G01Y414173D02*
Y244882D01*
G01Y608661D02*
Y439370D01*
G01X1400000D02*
G03X1407874I3937J0D01*
G01Y414173D02*
G03X1400000I-3937J0D01*
G01X1407874Y608661D02*
G03X1400000I-3937J0D01*
G01Y626378D02*
G03X1407874I3937J0D01*
G01Y795669D02*
Y626378D01*
G01Y795669D02*
G03X1400000I-3937J0D01*
G01Y820866D02*
G03X1407874I3937J0D01*
G01Y844488D02*
Y820866D01*
G01Y844488D02*
G03X1403937Y848425I-3937J0D01*
G01X1429670Y893701D02*
Y-47244D01*
G01X1425733Y-51181D02*
G03X1429670Y-47244I0J3937D01*
G01Y893701D02*
G03X1425733Y897638I-3937J0D01*
G54D12*
G01X197809Y312921D02*
X221066Y289664D01*
G01X219866Y289166D02*
X196609Y312423D01*
G01X197809Y328744D02*
Y312921D01*
G01X196609Y312423D02*
Y329242D01*
G01X206100Y337035D02*
X197809Y328744D01*
G01X196609Y329242D02*
X204900Y337533D01*
G01X196609Y329242D02*
X204900Y337533D01*
G01X206100Y337035D02*
X197809Y328744D01*
G01X196609Y312423D02*
Y329242D01*
G01X197809Y328744D02*
Y312921D01*
G01X219866Y289166D02*
X196609Y312423D01*
G01X197809Y312921D02*
X221066Y289664D01*
G01X190466Y505844D02*
X178000D01*
G01X188182Y507044D02*
X189968D01*
G01X183730D02*
X185344D01*
G01X179278D02*
X180892D01*
G01X195522Y510900D02*
X190466Y505844D01*
G01X193883Y510959D02*
X195024Y512100D01*
G01X189968Y507044D02*
X191876Y508952D01*
G01X201150Y510900D02*
X195522D01*
G01X195024Y512100D02*
X197555D01*
G01X195024D02*
X197555D01*
G01X201150Y510900D02*
X195522D01*
G01X193883Y510959D02*
X195024Y512100D01*
G01X195522Y510900D02*
X190466Y505844D01*
G01X189968Y507044D02*
X191876Y508952D01*
G01X195522Y510900D02*
X190466Y505844D01*
G01X188182Y507044D02*
X189968D01*
G01X190466Y505844D02*
X178000D01*
G01X183730Y507044D02*
X185344D01*
G01X190466Y505844D02*
X178000D01*
G01X179278Y507044D02*
X180892D01*
G01X190466Y505844D02*
X178000D01*
G01X186500Y828697D02*
Y871953D01*
G01X185300Y828697D02*
Y872000D01*
G01X186788Y827527D02*
G02X186500Y828697I2233J1170D01*
G01X185725Y826968D02*
G02X185300Y828697I3296J1727D01*
G01X187264Y827240D02*
G02X186788Y827527I0J538D01*
G01X187264Y826040D02*
G02X185725Y826968I-1J1739D01*
G01X195321Y827240D02*
X187264D01*
G01X195320Y826040D02*
X187264D01*
G01X197055Y826975D02*
G03X195321Y827240I-1734J-5540D01*
G01X196696Y825829D02*
G03X195320Y826040I-1378J-4394D01*
G01X196776Y825803D02*
G03X196696Y825829I-1463J-4366D01*
G01X197158Y826942D02*
G03X197055Y826975I-1206J-3587D01*
G01X198350Y824337D02*
G03X196778Y825803I-2388J-985D01*
G01X199460Y824795D02*
G03X197158Y826942I-3498J-1443D01*
G01X198350Y824337D02*
G03X196778Y825803I-2388J-985D01*
G01X198425Y824154D02*
X198350Y824337D01*
G01X198499Y823780D02*
G03X198425Y824154I-982J0D01*
G01X198499Y823526D02*
Y823780D01*
G01X197973Y822254D02*
G03X198499Y823526I-1273J1271D01*
G01D02*
Y823780D01*
G01X185300Y828697D02*
Y872000D01*
G01X186500Y828697D02*
Y871953D01*
G01X185725Y826968D02*
G02X185300Y828697I3296J1727D01*
G01X186788Y827527D02*
G02X186500Y828697I2233J1170D01*
G01X187264Y826040D02*
G02X185725Y826968I-1J1739D01*
G01X187264Y827240D02*
G02X186788Y827527I0J538D01*
G01X195320Y826040D02*
X187264D01*
G01X195321Y827240D02*
X187264D01*
G01X196696Y825829D02*
G03X195320Y826040I-1378J-4394D01*
G01X197055Y826975D02*
G03X195321Y827240I-1734J-5540D01*
G01X196776Y825803D02*
G03X196696Y825829I-1463J-4366D01*
G01X197055Y826975D02*
G03X195321Y827240I-1734J-5540D01*
G01X198350Y824337D02*
G03X196778Y825803I-2388J-985D01*
G01X197158Y826942D02*
G03X197055Y826975I-1206J-3587D01*
G01X199460Y824795D02*
G03X197158Y826942I-3498J-1443D01*
G01X198425Y824154D02*
X198350Y824337D01*
G01X198499Y823780D02*
G03X198425Y824154I-982J0D01*
G01X198499Y823526D02*
Y823780D01*
G01X197973Y822254D02*
G03X198499Y823526I-1273J1271D01*
G01X198218Y880300D02*
Y874090D01*
G01X198219Y882628D02*
Y880301D01*
G01X198218Y880300D02*
Y874090D01*
G01X198219Y882628D02*
Y880301D01*
G01X189971Y878800D02*
Y884370D01*
G01X188771Y882101D02*
Y884428D01*
G01X188770Y878500D02*
Y882100D01*
G01X189970Y878499D02*
Y878800D01*
G01X188770Y878500D02*
Y882100D01*
G01X189794Y877302D02*
G03X189970Y878499I-3994J1199D01*
G01X188645Y877647D02*
G03X188770Y878500I-2845J853D01*
G01X188749Y875551D02*
G03X189795Y877302I-2949J2949D01*
G01X188645Y877647D02*
G03X188770Y878500I-2845J853D01*
G01X187900Y876400D02*
G03X188645Y877647I-2100J2101D01*
G01X187454Y874256D02*
X188749Y875551D01*
G01X186573Y875073D02*
X187900Y876400D01*
G01X188771Y882101D02*
Y884428D01*
G01X189971Y878800D02*
Y884370D01*
G01X188770Y878500D02*
Y882100D01*
G01X189971Y878800D02*
Y884370D01*
G01X189970Y878499D02*
Y878800D01*
G01X188645Y877647D02*
G03X188770Y878500I-2845J853D01*
G01X189794Y877302D02*
G03X189970Y878499I-3994J1199D01*
G01X188749Y875551D02*
G03X189795Y877302I-2949J2949D01*
G01X187900Y876400D02*
G03X188645Y877647I-2100J2101D01*
G01X188749Y875551D02*
G03X189795Y877302I-2949J2949D01*
G01X186573Y875073D02*
X187900Y876400D01*
G01X187454Y874256D02*
X188749Y875551D01*
G01X208640Y189718D02*
Y198242D01*
G01X207440Y189635D02*
Y198324D01*
G01Y189635D02*
Y198324D01*
G01X208640Y189718D02*
Y198242D01*
G01X208681Y237224D02*
Y207917D01*
G01X207481D02*
Y237722D01*
G01Y207917D02*
Y237722D01*
G01X208681Y237224D02*
Y207917D01*
G01X221066Y249609D02*
X208681Y237224D01*
G01X207481Y237722D02*
X219866Y250107D01*
G01X207481Y237722D02*
X219866Y250107D01*
G01X221066Y249609D02*
X208681Y237224D01*
G01X221066Y289664D02*
Y249609D01*
G01X219866Y250107D02*
Y289166D01*
G01Y250107D02*
Y289166D01*
G01X221066Y289664D02*
Y249609D01*
G01X228741Y289061D02*
X245340D01*
G01X229239Y290261D02*
X245838D01*
G01X201993Y315809D02*
X228741Y289061D01*
G01X203193Y316307D02*
X229239Y290261D01*
G01D02*
X245838D01*
G01X228741Y289061D02*
X245340D01*
G01X203193Y316307D02*
X229239Y290261D01*
G01X201993Y315809D02*
X228741Y289061D01*
G01X201993Y327500D02*
Y315809D01*
G01X203193Y327002D02*
Y316307D01*
G01X210717Y336224D02*
X201993Y327500D01*
G01X211917Y335726D02*
X203193Y327002D01*
G01X210717Y344017D02*
Y336224D01*
G01X211917Y343519D02*
Y335726D01*
G01X225200Y358500D02*
X210717Y344017D01*
G01X225698Y357300D02*
X211917Y343519D01*
G01X203193Y327002D02*
Y316307D01*
G01X201993Y327500D02*
Y315809D01*
G01X211917Y335726D02*
X203193Y327002D01*
G01X210717Y336224D02*
X201993Y327500D01*
G01X211917Y343519D02*
Y335726D01*
G01X210717Y344017D02*
Y336224D01*
G01X225698Y357300D02*
X211917Y343519D01*
G01X225200Y358500D02*
X210717Y344017D01*
G01X206100Y352902D02*
Y337035D01*
G01X204900Y337533D02*
Y353400D01*
G01Y337533D02*
Y353400D01*
G01X206100Y352902D02*
Y337035D01*
G01X231184Y358500D02*
X225200D01*
G01X231682Y357300D02*
X225698D01*
G01X287900Y415212D02*
X231184Y358500D01*
G01X289100Y414714D02*
X231682Y357300D01*
G01D02*
X225698D01*
G01X231184Y358500D02*
X225200D01*
G01X289100Y414714D02*
X231682Y357300D01*
G01X287900Y415212D02*
X231184Y358500D01*
G01X270900Y417702D02*
X206100Y352902D01*
G01X204900Y353400D02*
X251654Y400154D01*
G01X270900Y417702D02*
X206100Y352902D01*
G01X270900Y417702D02*
X206100Y352902D01*
G01X270900Y417702D02*
X206100Y352902D01*
G01X270900Y417702D02*
X206100Y352902D01*
G01X204900Y353400D02*
X251654Y400154D01*
G01X270900Y417702D02*
X206100Y352902D01*
G01X225167Y510569D02*
X237867D01*
G01X224669Y511769D02*
X237369D01*
G01X222369Y507771D02*
X225167Y510569D01*
G01X221169Y508269D02*
X224669Y511769D01*
G01X222369Y507427D02*
Y507771D01*
G01X221169Y507925D02*
Y508269D01*
G01X220573Y505631D02*
X222369Y507427D01*
G01X220075Y506831D02*
X221169Y507925D01*
G01X218027Y505631D02*
X220573D01*
G01X218525Y506831D02*
X220075D01*
G01X215710Y505692D02*
X217966D01*
G01X216208Y506892D02*
X218464D01*
G01X209453Y511949D02*
X215710Y505692D01*
G01X210302Y512798D02*
X216208Y506892D01*
G01X208442Y512368D02*
G02X209453Y511949I0J-1429D01*
G01X206930Y512368D02*
X208442D01*
G01X224669Y511769D02*
X237369D01*
G01X225167Y510569D02*
X237867D01*
G01X221169Y508269D02*
X224669Y511769D01*
G01X222369Y507771D02*
X225167Y510569D01*
G01X221169Y507925D02*
Y508269D01*
G01X222369Y507427D02*
Y507771D01*
G01X220075Y506831D02*
X221169Y507925D01*
G01X220573Y505631D02*
X222369Y507427D01*
G01X218525Y506831D02*
X220075D01*
G01X218027Y505631D02*
X220573D01*
G01X216208Y506892D02*
X218464D01*
G01X215710Y505692D02*
X217966D01*
G01X210302Y512798D02*
X216208Y506892D01*
G01X209453Y511949D02*
X215710Y505692D01*
G01X208442Y512368D02*
G02X209453Y511949I0J-1429D01*
G01X206930Y512368D02*
X208442D01*
G01X208441Y513568D02*
G02X210302Y512798I2J-2629D01*
G01X206827Y513568D02*
X208441D01*
G01D02*
G02X210302Y512798I2J-2629D01*
G01X206827Y513568D02*
X208441D01*
G01X199536Y824610D02*
X199460Y824795D01*
G01X199699Y823780D02*
G03X199536Y824610I-2183J2D01*
G01X199699Y823526D02*
Y823780D01*
G01X199700Y823524D02*
G03X199699Y823526I-2683J-1340D01*
G01X199700Y823400D02*
Y823524D01*
G01X199536Y824610D02*
X199460Y824795D01*
G01X199699Y823780D02*
G03X199536Y824610I-2183J2D01*
G01X199699Y823526D02*
Y823780D01*
G01X199700Y823400D02*
Y823524D01*
G01D02*
G03X199699Y823526I-2683J-1340D01*
G01X210817Y880300D02*
Y877590D01*
G01X212018Y882570D02*
Y877588D01*
G01X210818Y882628D02*
Y880301D01*
G01X212018Y882570D02*
Y877588D01*
G01X223415Y880300D02*
Y877590D01*
G01X224616Y882570D02*
Y877588D01*
G01X223416Y882628D02*
Y880301D01*
G01X224616Y882570D02*
Y877588D01*
G01X199419Y882570D02*
Y873000D01*
G01X212018Y882570D02*
Y877588D01*
G01X210817Y880300D02*
Y877590D01*
G01X210818Y882628D02*
Y880301D01*
G01X224616Y882570D02*
Y877588D01*
G01X223415Y880300D02*
Y877590D01*
G01X223416Y882628D02*
Y880301D01*
G01X199419Y882570D02*
Y873000D01*
G01Y882570D02*
Y873000D01*
G01X245340Y289061D02*
X305451Y228950D01*
G01X245838Y290261D02*
X305949Y230150D01*
G01X245838Y290261D02*
X305949Y230150D01*
G01X245340Y289061D02*
X305451Y228950D01*
G01X263105Y411605D02*
X269700Y418200D01*
G01X259957Y408457D02*
X261098Y409598D01*
G01X256809Y405309D02*
X257950Y406450D01*
G01X253661Y402161D02*
X254802Y403302D01*
G01X263105Y411605D02*
X269700Y418200D01*
G01X259957Y408457D02*
X261098Y409598D01*
G01X256809Y405309D02*
X257950Y406450D01*
G01X253661Y402161D02*
X254802Y403302D01*
G01X237867Y510569D02*
X245397Y518099D01*
G01X237369Y511769D02*
X244899Y519299D01*
G01X237369Y511769D02*
X244899Y519299D01*
G01X237867Y510569D02*
X245397Y518099D01*
G01X259865Y509775D02*
X275735D01*
G01X275237Y508575D02*
X260363D01*
G01X258224Y508134D02*
X259865Y509775D01*
G01X260363Y508575D02*
X259424Y507636D01*
G01X258224Y503691D02*
Y508134D01*
G01X259424Y507636D02*
Y503657D01*
G01Y507636D02*
Y503657D01*
G01X258224Y503691D02*
Y508134D01*
G01X260363Y508575D02*
X259424Y507636D01*
G01X258224Y508134D02*
X259865Y509775D01*
G01X275237Y508575D02*
X260363D01*
G01X259865Y509775D02*
X275735D01*
G01X245397Y518099D02*
X284485D01*
G01X244899Y519299D02*
X284983D01*
G01X244899D02*
X284983D01*
G01X245397Y518099D02*
X284485D01*
G01X236013Y880300D02*
Y877590D01*
G01X237214Y882570D02*
Y877588D01*
G01X236014Y882628D02*
Y880301D01*
G01X237214Y882570D02*
Y877588D01*
G01X258061Y880300D02*
Y877590D01*
G01X259262Y882570D02*
Y877588D01*
G01X258062Y882628D02*
Y880301D01*
G01X259262Y882570D02*
Y877588D01*
G01X237214Y882570D02*
Y877588D01*
G01X236013Y880300D02*
Y877590D01*
G01X236014Y882628D02*
Y880301D01*
G01X259262Y882570D02*
Y877588D01*
G01X258061Y880300D02*
Y877590D01*
G01X258062Y882628D02*
Y880301D01*
G01X287900Y467716D02*
Y415212D01*
G01X289100Y467218D02*
Y414714D01*
G01Y467218D02*
Y414714D01*
G01X287900Y467716D02*
Y415212D01*
G01X270900Y466500D02*
Y417702D01*
G01X269700Y418200D02*
Y466998D01*
G01Y418200D02*
Y466998D01*
G01X270900Y466500D02*
Y417702D01*
G01X289307Y469123D02*
X287900Y467716D01*
G01X290507Y468625D02*
X289100Y467218D01*
G01X289307Y478721D02*
Y469123D01*
G01X290507Y478223D02*
Y468625D01*
G01X294646Y484060D02*
X289307Y478721D01*
G01X295846Y483562D02*
X290507Y478223D01*
G01Y468625D02*
X289100Y467218D01*
G01X289307Y469123D02*
X287900Y467716D01*
G01X290507Y478223D02*
Y468625D01*
G01X289307Y478721D02*
Y469123D01*
G01X295846Y483562D02*
X290507Y478223D01*
G01X294646Y484060D02*
X289307Y478721D01*
G01X278830Y474430D02*
X270900Y466500D01*
G01X269700Y466998D02*
X277630Y474928D01*
G01X278830Y506680D02*
Y474430D01*
G01X277630Y474928D02*
Y506182D01*
G01Y474928D02*
Y506182D01*
G01X278830Y506680D02*
Y474430D01*
G01X269700Y466998D02*
X277630Y474928D01*
G01X278830Y474430D02*
X270900Y466500D01*
G01X294646Y507938D02*
Y484060D01*
G01X295846Y508436D02*
Y483562D01*
G01X284485Y518099D02*
X294646Y507938D01*
G01X284983Y519299D02*
X295846Y508436D01*
G01D02*
Y483562D01*
G01X294646Y507938D02*
Y484060D01*
G01X284983Y519299D02*
X295846Y508436D01*
G01X284485Y518099D02*
X294646Y507938D01*
G01X275735Y509775D02*
X278830Y506680D01*
G01X277630Y506182D02*
X275237Y508575D01*
G01X277630Y506182D02*
X275237Y508575D01*
G01X275735Y509775D02*
X278830Y506680D01*
G01X270659Y880300D02*
Y877590D01*
G01X271860Y882570D02*
Y877588D01*
G01X270660Y882628D02*
Y880301D01*
G01X271860Y882570D02*
Y877588D01*
G01X283258Y880300D02*
Y868513D01*
G01X284459Y882570D02*
Y868713D01*
G01X283259Y882628D02*
Y880301D01*
G01X284459Y882570D02*
Y868713D01*
G01X271860Y882570D02*
Y877588D01*
G01X270659Y880300D02*
Y877590D01*
G01X270660Y882628D02*
Y880301D01*
G01X284459Y882570D02*
Y868713D01*
G01X283258Y880300D02*
Y868513D01*
G01X283259Y882628D02*
Y880301D01*
G01X305451Y228950D02*
X342152D01*
G01X305949Y230150D02*
X342650D01*
G01X305949D02*
X342650D01*
G01X305451Y228950D02*
X342152D01*
G01X333651Y880300D02*
Y877590D01*
G01X333652Y882628D02*
Y880301D01*
G01X308455Y880300D02*
Y867366D01*
G01X309656Y882570D02*
Y867800D01*
G01X308456Y882628D02*
Y880301D01*
G01X309656Y882570D02*
Y867800D01*
G01X321053Y880300D02*
Y877590D01*
G01X322254Y882570D02*
Y877588D01*
G01X321054Y882628D02*
Y880301D01*
G01X322254Y882570D02*
Y877588D01*
G01X333651Y880300D02*
Y877590D01*
G01X333652Y882628D02*
Y880301D01*
G01X309656Y882570D02*
Y867800D01*
G01X308455Y880300D02*
Y867366D01*
G01X308456Y882628D02*
Y880301D01*
G01X322254Y882570D02*
Y877588D01*
G01X321053Y880300D02*
Y877590D01*
G01X321054Y882628D02*
Y880301D01*
G01X354592Y193612D02*
X392788Y155416D01*
G01X355792Y194110D02*
X393988Y155914D01*
G01X354592Y216510D02*
Y193612D01*
G01X355792Y217008D02*
Y194110D01*
G01D02*
X393988Y155914D01*
G01X354592Y193612D02*
X392788Y155416D01*
G01X355792Y217008D02*
Y194110D01*
G01X354592Y216510D02*
Y193612D01*
G01X342152Y228950D02*
X354592Y216510D01*
G01X342650Y230150D02*
X355792Y217008D01*
G01X342650Y230150D02*
X355792Y217008D01*
G01X342152Y228950D02*
X354592Y216510D01*
G01X346250Y880300D02*
Y877590D01*
G01X347451Y882570D02*
Y877588D01*
G01X346251Y882628D02*
Y880301D01*
G01X347451Y882570D02*
Y877588D01*
G01X358848Y880300D02*
Y877590D01*
G01X360049Y882570D02*
Y877588D01*
G01X358849Y882628D02*
Y880301D01*
G01X360049Y882570D02*
Y877588D01*
G01X334852Y882570D02*
Y877588D01*
G01X347451Y882570D02*
Y877588D01*
G01X346250Y880300D02*
Y877590D01*
G01X346251Y882628D02*
Y880301D01*
G01X360049Y882570D02*
Y877588D01*
G01X358848Y880300D02*
Y877590D01*
G01X358849Y882628D02*
Y880301D01*
G01X334852Y882570D02*
Y877588D01*
G01Y882570D02*
Y877588D01*
G01X392788Y144514D02*
X421749Y115553D01*
G01X393988Y145012D02*
X422247Y116753D01*
G01X393988Y145012D02*
X422247Y116753D01*
G01X392788Y144514D02*
X421749Y115553D01*
G01X392788Y155416D02*
Y144514D01*
G01X393988Y155914D02*
Y145012D01*
G01Y155914D02*
Y145012D01*
G01X392788Y155416D02*
Y144514D01*
G01X369700Y726255D02*
Y725837D01*
G01X368500Y724992D02*
Y729416D01*
G01X369700Y729311D02*
Y726277D01*
G01X368500Y724992D02*
Y729416D01*
G01X371902Y741797D02*
X369700Y729311D01*
G01X368500Y729416D02*
X370766Y742267D01*
G01X380771Y754463D02*
X371902Y741797D01*
G01X370766Y742267D02*
X379909Y755325D01*
G01X370766Y742267D02*
X379909Y755325D01*
G01X380771Y754463D02*
X371902Y741797D01*
G01X368500Y729416D02*
X370766Y742267D01*
G01X371902Y741797D02*
X369700Y729311D01*
G01X368500Y724992D02*
Y729416D01*
G01X369700Y726255D02*
Y725837D01*
G01Y729311D02*
Y726277D01*
G01X402138Y769425D02*
X380771Y754463D01*
G01X379909Y755325D02*
X401276Y770287D01*
G01D02*
X433247Y815947D01*
G01X401276Y770287D02*
X433247Y815947D01*
G01X401276Y770287D02*
X433247Y815947D01*
G01X401276Y770287D02*
X433247Y815947D01*
G01X401276Y770287D02*
X433247Y815947D01*
G01X379909Y755325D02*
X401276Y770287D01*
G01X402138Y769425D02*
X380771Y754463D01*
G01X380896Y880300D02*
Y877590D01*
G01X382097Y882570D02*
Y877588D01*
G01X380897Y882628D02*
Y880301D01*
G01X382097Y882570D02*
Y877588D01*
G01X393494Y880300D02*
Y877590D01*
G01X394695Y882570D02*
Y877588D01*
G01X393495Y882628D02*
Y880301D01*
G01X394695Y882570D02*
Y877588D01*
G01X382097Y882570D02*
Y877588D01*
G01X380896Y880300D02*
Y877590D01*
G01X380897Y882628D02*
Y880301D01*
G01X394695Y882570D02*
Y877588D01*
G01X393494Y880300D02*
Y877590D01*
G01X393495Y882628D02*
Y880301D01*
G01X434547Y115553D02*
X455300Y94800D01*
G01X435045Y116753D02*
X455798Y96000D01*
G01X421749Y115553D02*
X434547D01*
G01X422247Y116753D02*
X435045D01*
G01D02*
X455798Y96000D01*
G01X434547Y115553D02*
X455300Y94800D01*
G01X422247Y116753D02*
X435045D01*
G01X421749Y115553D02*
X434547D01*
G01X421002Y796366D02*
X402138Y769425D01*
G01X421002Y796366D02*
X402138Y769425D01*
G01X423601Y800078D02*
X422675Y798756D01*
G01X426200Y803790D02*
X425274Y802468D01*
G01X434383Y815477D02*
X427873Y806179D01*
G01X437507Y833195D02*
X434383Y815477D01*
G01X433247Y815947D02*
X436307Y833300D01*
G01X433247Y815947D02*
X436307Y833300D01*
G01X437507Y833195D02*
X434383Y815477D01*
G01X423601Y800078D02*
X422675Y798756D01*
G01X426200Y803790D02*
X425274Y802468D01*
G01X434383Y815477D02*
X427873Y806179D01*
G01X406092Y880300D02*
Y877590D01*
G01X407293Y882570D02*
Y877588D01*
G01X406093Y882628D02*
Y880301D01*
G01X407293Y882570D02*
Y877588D01*
G01X418691Y880300D02*
Y877590D01*
G01X419892Y882570D02*
Y877588D01*
G01X418692Y882628D02*
Y880301D01*
G01X419892Y882570D02*
Y877588D01*
G01X407293Y882570D02*
Y877588D01*
G01X406092Y880300D02*
Y877590D01*
G01X406093Y882628D02*
Y880301D01*
G01X419892Y882570D02*
Y877588D01*
G01X418691Y880300D02*
Y877590D01*
G01X418692Y882628D02*
Y880301D01*
G01X436150Y866352D02*
X434936Y867565D01*
G01D02*
G02X434440Y868767I1204J1200D01*
G01Y882101D02*
Y884428D01*
G01Y868767D02*
Y881150D01*
G01Y882101D02*
Y884428D01*
G01Y868767D02*
Y881150D01*
G01X434936Y867565D02*
G02X434440Y868767I1204J1200D01*
G01X436150Y866352D02*
X434936Y867565D01*
G01X464789Y94800D02*
X498993Y60596D01*
G01X465287Y96000D02*
X500193Y61094D01*
G01X455300Y94800D02*
X464789D01*
G01X455798Y96000D02*
X465287D01*
G01D02*
X500193Y61094D01*
G01X464789Y94800D02*
X498993Y60596D01*
G01X455798Y96000D02*
X465287D01*
G01X455300Y94800D02*
X464789D01*
G01X437507Y862125D02*
Y833195D01*
G01X436307Y833300D02*
Y862623D01*
G01Y833300D02*
Y862623D01*
G01X437507Y862125D02*
Y833195D01*
G01X437508Y866485D02*
Y862126D01*
G01X436308Y862624D02*
Y865971D01*
G01X435786Y868414D02*
X437362Y866838D01*
G01X435640Y868767D02*
G03X435786Y868414I500J0D01*
G01X435640Y884370D02*
Y868767D01*
G01Y884370D02*
Y868767D01*
G01Y884370D02*
Y868767D01*
G01D02*
G03X435786Y868414I500J0D01*
G01D02*
X437362Y866838D01*
G01X436308Y862624D02*
Y865971D01*
G01X437508Y866485D02*
Y862126D01*
G01X498993Y28611D02*
X522782Y4822D01*
G01X500193Y29109D02*
X523280Y6022D01*
G01X498993Y60596D02*
Y28611D01*
G01X500193Y61094D02*
Y29109D01*
G01D02*
X523280Y6022D01*
G01X498993Y28611D02*
X522782Y4822D01*
G01X500193Y61094D02*
Y29109D01*
G01X498993Y60596D02*
Y28611D01*
G01X522782Y4822D02*
X699520D01*
G01X523280Y6022D02*
X700018D01*
G01X523280D02*
X700018D01*
G01X522782Y4822D02*
X699520D01*
G01X519381Y33552D02*
Y46266D01*
G01X520581Y33553D02*
Y46266D01*
G01X520570Y30682D02*
G02X519381Y33552I2871J2871D01*
G01X521419Y31531D02*
G02X520581Y33553I2022J2023D01*
G01X531266Y19986D02*
X520570Y30682D01*
G01X525819Y27131D02*
X521419Y31531D01*
G01X526684Y27131D02*
X525819D01*
G01X528967Y23983D02*
X527826Y25124D01*
G01X529832Y23983D02*
X528967D01*
G01X532115Y20835D02*
X530974Y21976D01*
G01X535596Y18193D02*
G02X531266Y19986I-1J6123D01*
G01X535596Y19393D02*
G02X532115Y20835I0J4923D01*
G01X694738Y18193D02*
X535596D01*
G01X676930Y19393D02*
X535596D01*
G01X520581Y33553D02*
Y46266D01*
G01X519381Y33552D02*
Y46266D01*
G01X521419Y31531D02*
G02X520581Y33553I2022J2023D01*
G01X520570Y30682D02*
G02X519381Y33552I2871J2871D01*
G01X525819Y27131D02*
X521419Y31531D01*
G01X531266Y19986D02*
X520570Y30682D01*
G01X526684Y27131D02*
X525819D01*
G01X531266Y19986D02*
X520570Y30682D01*
G01X528967Y23983D02*
X527826Y25124D01*
G01X531266Y19986D02*
X520570Y30682D01*
G01X529832Y23983D02*
X528967D01*
G01X531266Y19986D02*
X520570Y30682D01*
G01X532115Y20835D02*
X530974Y21976D01*
G01X531266Y19986D02*
X520570Y30682D01*
G01X535596Y19393D02*
G02X532115Y20835I0J4923D01*
G01X535596Y18193D02*
G02X531266Y19986I-1J6123D01*
G01X676930Y19393D02*
X535596D01*
G01X694738Y18193D02*
X535596D01*
G01X694738D02*
X535596D01*
G01X694738D02*
X535596D01*
G01X694738D02*
X535596D01*
G01X694738D02*
X535596D01*
G01X524867Y52362D02*
X524869Y52363D01*
G01X522899Y49942D02*
X525435Y51304D01*
G01X524868Y52362D02*
X524867D01*
G01X522899Y49942D02*
X525435Y51304D01*
G01X522175Y50916D02*
X524868Y52362D01*
G01X522899Y49942D02*
X525435Y51304D01*
G01X520692Y49433D02*
X522175Y50916D01*
G01X521541Y48584D02*
X522899Y49942D01*
G01X519381Y46266D02*
G02X520692Y49433I4479J1D01*
G01X520581Y46266D02*
G02X521541Y48584I3279J0D01*
G01X522899Y49942D02*
X525435Y51304D01*
G01X524867Y52362D02*
X524869Y52363D01*
G01X524868Y52362D02*
X524867D01*
G01X522175Y50916D02*
X524868Y52362D01*
G01X521541Y48584D02*
X522899Y49942D01*
G01X520692Y49433D02*
X522175Y50916D01*
G01X520581Y46266D02*
G02X521541Y48584I3279J0D01*
G01X519381Y46266D02*
G02X520692Y49433I4479J1D01*
G01X539951Y880300D02*
Y877590D01*
G01X541152Y882570D02*
Y877588D01*
G01X539952Y882628D02*
Y880301D01*
G01X541152Y882570D02*
Y877588D01*
G01X552550Y880300D02*
Y877590D01*
G01X553751Y882570D02*
Y877588D01*
G01X552551Y882628D02*
Y880301D01*
G01X553751Y882570D02*
Y877588D01*
G01X565148Y880300D02*
Y877590D01*
G01X566349Y882570D02*
Y877588D01*
G01X565149Y882628D02*
Y880301D01*
G01X566349Y882570D02*
Y877588D01*
G01X541152Y882570D02*
Y877588D01*
G01X539951Y880300D02*
Y877590D01*
G01X539952Y882628D02*
Y880301D01*
G01X553751Y882570D02*
Y877588D01*
G01X552550Y880300D02*
Y877590D01*
G01X552551Y882628D02*
Y880301D01*
G01X566349Y882570D02*
Y877588D01*
G01X565148Y880300D02*
Y877590D01*
G01X565149Y882628D02*
Y880301D01*
G01X602944Y880300D02*
Y877590D01*
G01X602945Y882628D02*
Y880301D01*
G01X577747Y880300D02*
Y877590D01*
G01X578948Y882570D02*
Y877588D01*
G01X577748Y882628D02*
Y880301D01*
G01X578948Y882570D02*
Y877588D01*
G01X590345Y880300D02*
Y877590D01*
G01X591546Y882570D02*
Y877588D01*
G01X590346Y882628D02*
Y880301D01*
G01X591546Y882570D02*
Y877588D01*
G01X602944Y880300D02*
Y877590D01*
G01X602945Y882628D02*
Y880301D01*
G01X578948Y882570D02*
Y877588D01*
G01X577747Y880300D02*
Y877590D01*
G01X577748Y882628D02*
Y880301D01*
G01X591546Y882570D02*
Y877588D01*
G01X590345Y880300D02*
Y877590D01*
G01X590346Y882628D02*
Y880301D01*
G01X607321Y31008D02*
Y48228D01*
G01X608521Y31008D02*
Y39324D01*
G01X608372Y28469D02*
G02X607321Y31008I2539J2538D01*
G01X609221Y29318D02*
G02X608521Y31008I1690J1690D01*
G01X611515Y25326D02*
X608372Y28469D01*
G01X612364Y26175D02*
X609221Y29318D01*
G01X614554Y24067D02*
G02X611515Y25326I1J4299D01*
G01X614555Y25267D02*
G02X612364Y26175I1J3099D01*
G01X681561Y24067D02*
X614554D01*
G01X681561Y25267D02*
X614555D01*
G01X607321Y31008D02*
Y48228D01*
G01Y31008D02*
Y48228D01*
G01X608521Y31008D02*
Y39324D01*
G01X607321Y31008D02*
Y48228D01*
G01X609221Y29318D02*
G02X608521Y31008I1690J1690D01*
G01X608372Y28469D02*
G02X607321Y31008I2539J2538D01*
G01X612364Y26175D02*
X609221Y29318D01*
G01X611515Y25326D02*
X608372Y28469D01*
G01X614555Y25267D02*
G02X612364Y26175I1J3099D01*
G01X614554Y24067D02*
G02X611515Y25326I1J4299D01*
G01X681561Y25267D02*
X614555D01*
G01X681561Y24067D02*
X614554D01*
G01X609032Y51051D02*
X611483Y52361D01*
G01X609755Y50076D02*
X612049Y51302D01*
G01X608106Y50125D02*
X609032Y51051D01*
G01X608955Y49276D02*
X609755Y50076D01*
G01X607321Y48228D02*
G02X608106Y50125I2683J1D01*
G01X608521Y48228D02*
G02X608955Y49276I1482J0D01*
G01X608521Y46614D02*
Y48228D01*
G01Y42162D02*
Y43776D01*
G01X609755Y50076D02*
X612049Y51302D01*
G01X609032Y51051D02*
X611483Y52361D01*
G01X608955Y49276D02*
X609755Y50076D01*
G01X608106Y50125D02*
X609032Y51051D01*
G01X608521Y48228D02*
G02X608955Y49276I1482J0D01*
G01X607321Y48228D02*
G02X608106Y50125I2683J1D01*
G01X608521Y46614D02*
Y48228D01*
G01Y42162D02*
Y43776D01*
G01X615542Y880300D02*
Y877590D01*
G01X616743Y882570D02*
Y876400D01*
G01X615543Y882628D02*
Y880301D01*
G01X616743Y882570D02*
Y876400D01*
G01X628140Y880300D02*
Y877590D01*
G01X629341Y882570D02*
Y877588D01*
G01X628141Y882628D02*
Y880301D01*
G01X629341Y882570D02*
Y877588D01*
G01X604145Y882570D02*
Y877588D01*
G01X616743Y882570D02*
Y876400D01*
G01X615542Y880300D02*
Y877590D01*
G01X615543Y882628D02*
Y880301D01*
G01X629341Y882570D02*
Y877588D01*
G01X628140Y880300D02*
Y877590D01*
G01X628141Y882628D02*
Y880301D01*
G01X604145Y882570D02*
Y877588D01*
G01Y882570D02*
Y877588D01*
G01X650188Y880300D02*
Y877590D01*
G01X651389Y882570D02*
Y877588D01*
G01X650189Y882628D02*
Y880301D01*
G01X651389Y882570D02*
Y877588D01*
G01X662786Y880300D02*
Y877590D01*
G01X663987Y882570D02*
Y877588D01*
G01X662787Y882628D02*
Y880301D01*
G01X663987Y882570D02*
Y877588D01*
G01X651389Y882570D02*
Y877588D01*
G01X650188Y880300D02*
Y877590D01*
G01X650189Y882628D02*
Y880301D01*
G01X663987Y882570D02*
Y877588D01*
G01X662786Y880300D02*
Y877590D01*
G01X662787Y882628D02*
Y880301D01*
G01X699520Y4822D02*
X717189Y-12847D01*
G01X700018Y6022D02*
X717687Y-11647D01*
G01X700018Y6022D02*
X717687Y-11647D01*
G01X699520Y4822D02*
X717189Y-12847D01*
G01X685232Y25587D02*
G02X681561Y24067I-3670J3671D01*
G01X684383Y26436D02*
G02X681561Y25267I-2822J2822D01*
G01X709525Y49880D02*
X685232Y25587D01*
G01X696084Y38137D02*
X684383Y26436D01*
G01X698091Y40144D02*
X697225D01*
G01X699232Y41285D02*
X698091Y40144D01*
G01X684383Y26436D02*
G02X681561Y25267I-2822J2822D01*
G01X685232Y25587D02*
G02X681561Y24067I-3670J3671D01*
G01X696084Y38137D02*
X684383Y26436D01*
G01X709525Y49880D02*
X685232Y25587D01*
G01X698091Y40144D02*
X697225D01*
G01X709525Y49880D02*
X685232Y25587D01*
G01X699232Y41285D02*
X698091Y40144D01*
G01X709525Y49880D02*
X685232Y25587D01*
G01X709525Y49880D02*
X685232Y25587D01*
G01X709525Y49880D02*
X685232Y25587D01*
G01X709525Y49880D02*
X685232Y25587D01*
G01X709525Y49880D02*
X685232Y25587D01*
G01X709525Y49880D02*
X685232Y25587D01*
G01X709525Y49880D02*
X685232Y25587D01*
G01X681382Y19393D02*
X679768D01*
G01X685834D02*
X684220D01*
G01X690286D02*
X688672D01*
G01X694738D02*
X693124D01*
G01X699348Y20102D02*
G02X694738Y18193I-4609J4610D01*
G01X698499Y20951D02*
G02X694738Y19393I-3761J3761D01*
G01X705348Y26102D02*
X699348Y20102D01*
G01X704499Y26951D02*
X698499Y20951D01*
G01X707197Y28068D02*
G03X704499Y26951I-1J-3815D01*
G01X681382Y19393D02*
X679768D01*
G01X685834D02*
X684220D01*
G01X690286D02*
X688672D01*
G01X694738D02*
X693124D01*
G01X698499Y20951D02*
G02X694738Y19393I-3761J3761D01*
G01X699348Y20102D02*
G02X694738Y18193I-4609J4610D01*
G01X704499Y26951D02*
X698499Y20951D01*
G01X705348Y26102D02*
X699348Y20102D01*
G01X707197Y28068D02*
G03X704499Y26951I-1J-3815D01*
G01X701239Y43292D02*
X700373D01*
G01X702380Y44433D02*
X701239Y43292D01*
G01X704387Y46440D02*
X703521D01*
G01X705528Y47581D02*
X704387Y46440D01*
G01X701239Y43292D02*
X700373D01*
G01X702380Y44433D02*
X701239Y43292D01*
G01X704387Y46440D02*
X703521D01*
G01X705528Y47581D02*
X704387Y46440D01*
G01X675385Y880300D02*
Y877590D01*
G01X676586Y882570D02*
Y877588D01*
G01X675386Y882628D02*
Y880301D01*
G01X676586Y882570D02*
Y877588D01*
G01X687983Y880300D02*
Y877590D01*
G01X689184Y882570D02*
Y877588D01*
G01X687984Y882628D02*
Y880301D01*
G01X689184Y882570D02*
Y877588D01*
G01X700581Y880300D02*
Y871178D01*
G01X701782Y882570D02*
Y870292D01*
G01X700582Y882628D02*
Y880301D01*
G01X701782Y882570D02*
Y870292D01*
G01X676586Y882570D02*
Y877588D01*
G01X675385Y880300D02*
Y877590D01*
G01X675386Y882628D02*
Y880301D01*
G01X689184Y882570D02*
Y877588D01*
G01X687983Y880300D02*
Y877590D01*
G01X687984Y882628D02*
Y880301D01*
G01X701782Y882570D02*
Y870292D01*
G01X700581Y880300D02*
Y871178D01*
G01X700582Y882628D02*
Y880301D01*
G01X717189Y-12847D02*
X779260D01*
G01X717687Y-11647D02*
X779758D01*
G01X717687D02*
X779758D01*
G01X717189Y-12847D02*
X779260D01*
G01X723740Y28380D02*
G02X721359Y27085I-3381J3380D01*
G01X722891Y29229D02*
G02X721109Y28259I-2532J2530D01*
G01X724074Y28714D02*
X723740Y28380D01*
G01X723225Y29563D02*
X722891Y29229D01*
G01X725156Y31327D02*
G02X724074Y28714I-3694J-1D01*
G01X723955Y31327D02*
G02X723225Y29563I-2493J-1D01*
G01X725155Y32095D02*
Y31327D01*
G01X723955Y32095D02*
Y31327D01*
G01X722891Y29229D02*
G02X721109Y28259I-2532J2530D01*
G01X723740Y28380D02*
G02X721359Y27085I-3381J3380D01*
G01X723225Y29563D02*
X722891Y29229D01*
G01X724074Y28714D02*
X723740Y28380D01*
G01X723955Y31327D02*
G02X723225Y29563I-2493J-1D01*
G01X725156Y31327D02*
G02X724074Y28714I-3694J-1D01*
G01X723955Y32095D02*
Y31327D01*
G01X725155Y32095D02*
Y31327D01*
G01X723740Y28380D02*
G02X721359Y27085I-3381J3380D01*
G01X722891Y29229D02*
G02X721109Y28259I-2532J2530D01*
G01X724074Y28714D02*
X723740Y28380D01*
G01X723225Y29563D02*
X722891Y29229D01*
G01X725156Y31327D02*
G02X724074Y28714I-3694J-1D01*
G01X723955Y31327D02*
G02X723225Y29563I-2493J-1D01*
G01X725155Y32095D02*
Y31327D01*
G01X723955Y32095D02*
Y31327D01*
G01X722891Y29229D02*
G02X721109Y28259I-2532J2530D01*
G01X723740Y28380D02*
G02X721359Y27085I-3381J3380D01*
G01X723225Y29563D02*
X722891Y29229D01*
G01X724074Y28714D02*
X723740Y28380D01*
G01X723955Y31327D02*
G02X723225Y29563I-2493J-1D01*
G01X725156Y31327D02*
G02X724074Y28714I-3694J-1D01*
G01X723955Y32095D02*
Y31327D01*
G01X725155Y32095D02*
Y31327D01*
G01X707197Y26868D02*
G03X705348Y26102I0J-2615D01*
G01X712150Y26868D02*
X707197D01*
G01X712600Y28068D02*
X707197D01*
G01Y26868D02*
G03X705348Y26102I0J-2615D01*
G01X712600Y28068D02*
X707197D01*
G01X712150Y26868D02*
X707197D01*
G01X721402Y49977D02*
G03X720743Y50249I-658J-660D01*
G01X720744Y51450D02*
G02X722251Y50826I0J-2132D01*
G01X723804Y47575D02*
X721402Y49977D01*
G01X724314Y48763D02*
X724653Y48424D01*
G01X723402Y49676D02*
X724314Y48764D01*
G01X722251Y50826D02*
X723402Y49676D01*
G01X725071Y47051D02*
G02X723804Y47575I-1J1792D01*
G01X724653Y48424D02*
G03X725071Y48251I418J418D01*
G01X725609Y47051D02*
X725071D01*
G01Y48251D02*
X725609D01*
G01X725071D02*
X725609D01*
G01Y47051D02*
X725071D01*
G01X724653Y48424D02*
G03X725071Y48251I418J418D01*
G01Y47051D02*
G02X723804Y47575I-1J1792D01*
G01X724314Y48763D02*
X724653Y48424D01*
G01X723804Y47575D02*
X721402Y49977D01*
G01X723402Y49676D02*
X724314Y48764D01*
G01X723804Y47575D02*
X721402Y49977D01*
G01X722251Y50826D02*
X723402Y49676D01*
G01X723804Y47575D02*
X721402Y49977D01*
G01X720744Y51450D02*
G02X722251Y50826I0J-2132D01*
G01X721402Y49977D02*
G03X720743Y50249I-658J-660D01*
G01X721402Y49977D02*
G03X720743Y50249I-658J-660D01*
G01X720744Y51450D02*
G02X722251Y50826I0J-2132D01*
G01X723804Y47575D02*
X721402Y49977D01*
G01X724314Y48763D02*
X724653Y48424D01*
G01X723402Y49676D02*
X724314Y48764D01*
G01X722251Y50826D02*
X723402Y49676D01*
G01X725071Y47051D02*
G02X723804Y47575I-1J1792D01*
G01X724653Y48424D02*
G03X725071Y48251I418J418D01*
G01X725609Y47051D02*
X725071D01*
G01Y48251D02*
X725609D01*
G01X725071D02*
X725609D01*
G01Y47051D02*
X725071D01*
G01X724653Y48424D02*
G03X725071Y48251I418J418D01*
G01Y47051D02*
G02X723804Y47575I-1J1792D01*
G01X724314Y48763D02*
X724653Y48424D01*
G01X723804Y47575D02*
X721402Y49977D01*
G01X723402Y49676D02*
X724314Y48764D01*
G01X723804Y47575D02*
X721402Y49977D01*
G01X722251Y50826D02*
X723402Y49676D01*
G01X723804Y47575D02*
X721402Y49977D01*
G01X720744Y51450D02*
G02X722251Y50826I0J-2132D01*
G01X721402Y49977D02*
G03X720743Y50249I-658J-660D01*
G01X707535Y49588D02*
X706669D01*
G01X708676Y50729D02*
X707535Y49588D01*
G01X710684Y50360D02*
G03X709525Y49880I0J-1639D01*
G01X710684Y51560D02*
G03X708676Y50729I-1J-2840D01*
G01X713820Y50360D02*
X710684D01*
G01X713440Y51560D02*
X710684D01*
G01X707535Y49588D02*
X706669D01*
G01X708676Y50729D02*
X707535Y49588D01*
G01X710684Y51560D02*
G03X708676Y50729I-1J-2840D01*
G01X710684Y50360D02*
G03X709525Y49880I0J-1639D01*
G01X713440Y51560D02*
X710684D01*
G01X713820Y50360D02*
X710684D01*
G01X732077Y880300D02*
Y877590D01*
G01X733278Y882570D02*
Y877588D01*
G01X732078Y882628D02*
Y880301D01*
G01X733278Y882570D02*
Y877588D01*
G01Y882570D02*
Y877588D01*
G01X732077Y880300D02*
Y877590D01*
G01X732078Y882628D02*
Y880301D01*
G01X744676Y880300D02*
Y877590D01*
G01X745877Y882570D02*
Y877588D01*
G01X744677Y882628D02*
Y880301D01*
G01X745877Y882570D02*
Y877588D01*
G01X757274Y880300D02*
Y877590D01*
G01X758475Y882570D02*
Y877588D01*
G01X757275Y882628D02*
Y880301D01*
G01X758475Y882570D02*
Y877588D01*
G01X769873Y880300D02*
Y877590D01*
G01X771074Y882570D02*
Y877588D01*
G01X769874Y882628D02*
Y880301D01*
G01X771074Y882570D02*
Y877588D01*
G01X745877Y882570D02*
Y877588D01*
G01X744676Y880300D02*
Y877590D01*
G01X744677Y882628D02*
Y880301D01*
G01X758475Y882570D02*
Y877588D01*
G01X757274Y880300D02*
Y877590D01*
G01X757275Y882628D02*
Y880301D01*
G01X771074Y882570D02*
Y877588D01*
G01X769873Y880300D02*
Y877590D01*
G01X769874Y882628D02*
Y880301D01*
G01X781045Y-14632D02*
X824967D01*
G01X781543Y-13432D02*
X824469D01*
G01X779260Y-12847D02*
X781045Y-14632D01*
G01X779758Y-11647D02*
X781543Y-13432D01*
G01D02*
X824469D01*
G01X781045Y-14632D02*
X824967D01*
G01X779758Y-11647D02*
X781543Y-13432D01*
G01X779260Y-12847D02*
X781045Y-14632D01*
G01X809272Y183913D02*
X801989Y189012D01*
G01X802764Y189936D02*
X807168Y186853D01*
G01X809272Y183913D02*
X801989Y189012D01*
G01X801900Y190800D02*
X802764Y189936D01*
G01X801131Y189871D02*
X801051Y189951D01*
G01X801989Y189012D02*
X801150Y189851D01*
G01X801200Y192490D02*
G03X801900Y190800I2390J0D01*
G01X801051Y189951D02*
G02X800000Y192490I2539J2538D01*
G01X801200Y193586D02*
Y192490D01*
G01X800000D02*
Y193587D01*
G01Y192490D02*
Y193587D01*
G01X801200Y193586D02*
Y192490D01*
G01X801051Y189951D02*
G02X800000Y192490I2539J2538D01*
G01X801200D02*
G03X801900Y190800I2390J0D01*
G01X801131Y189871D02*
X801051Y189951D01*
G01X801900Y190800D02*
X802764Y189936D01*
G01X801989Y189012D02*
X801150Y189851D01*
G01X801900Y190800D02*
X802764Y189936D01*
G01X809272Y183913D02*
X801989Y189012D01*
G01X802764Y189936D02*
X807168Y186853D01*
G01X782471Y880300D02*
Y877590D01*
G01X783672Y882570D02*
Y877588D01*
G01X782472Y882628D02*
Y880301D01*
G01X783672Y882570D02*
Y877588D01*
G01X795070Y880300D02*
Y877590D01*
G01X796271Y882570D02*
Y877588D01*
G01X795071Y882628D02*
Y880301D01*
G01X796271Y882570D02*
Y877588D01*
G01X783672Y882570D02*
Y877588D01*
G01X782471Y880300D02*
Y877590D01*
G01X782472Y882628D02*
Y880301D01*
G01X796271Y882570D02*
Y877588D01*
G01X795070Y880300D02*
Y877590D01*
G01X795071Y882628D02*
Y880301D01*
G01X826450Y-13149D02*
X896118D01*
G01X825952Y-11949D02*
X895620D01*
G01X824967Y-14632D02*
X826450Y-13149D01*
G01X824469Y-13432D02*
X825952Y-11949D01*
G01D02*
X895620D01*
G01X826450Y-13149D02*
X896118D01*
G01X824469Y-13432D02*
X825952Y-11949D01*
G01X824967Y-14632D02*
X826450Y-13149D01*
G01X838353Y178600D02*
X836206D01*
G01X836447Y177400D02*
X838352D01*
G01X839735Y178119D02*
G03X838353Y178600I-1381J-1743D01*
G01X838988Y177178D02*
G02X839076Y177100I-634J-804D01*
G01X838352Y177400D02*
G02X838988Y177178I-1J-1024D01*
G01X839924Y177950D02*
G03X839734Y178118I-1566J-1580D01*
G01X838988Y177178D02*
G02X839076Y177100I-634J-804D01*
G01X838352Y177400D02*
G02X838988Y177178I-1J-1024D01*
G01X839076Y177100D02*
G03X840324Y176387I1931J1931D01*
G01X839076Y177100D02*
G03X840324Y176387I1931J1931D01*
G01X839076Y177100D02*
G03X840324Y176387I1931J1931D01*
G01X838988Y177178D02*
G02X839076Y177100I-634J-804D01*
G01X839735Y178119D02*
G03X838353Y178600I-1381J-1743D01*
G01X839924Y177950D02*
G03X839734Y178118I-1566J-1580D01*
G01X838352Y177400D02*
G02X838988Y177178I-1J-1024D01*
G01X839735Y178119D02*
G03X838353Y178600I-1381J-1743D01*
G01X839924Y177950D02*
G03X839734Y178118I-1566J-1580D01*
G01X836447Y177400D02*
X838352D01*
G01X838353Y178600D02*
X836206D01*
G01X826766Y178550D02*
X828279D01*
G01Y177350D02*
X826580D01*
G01X812588Y183036D02*
X826766Y178550D01*
G01X826580Y177350D02*
X811946Y181979D01*
G01X812548Y183076D02*
X812588Y183036D01*
G01X811946Y181979D02*
X811739Y182187D01*
G01X809961Y184897D02*
X812474Y183139D01*
G01X811739Y182187D02*
X809272Y183913D01*
G01X807168Y186853D02*
X809961Y184897D01*
G01X807168Y186853D02*
X809961Y184897D01*
G01X811739Y182187D02*
X809272Y183913D01*
G01X809961Y184897D02*
X812474Y183139D01*
G01X811946Y181979D02*
X811739Y182187D01*
G01X812548Y183076D02*
X812588Y183036D01*
G01X826580Y177350D02*
X811946Y181979D01*
G01X812588Y183036D02*
X826766Y178550D01*
G01X828279Y177350D02*
X826580D01*
G01X826766Y178550D02*
X828279D01*
G01X807668Y880300D02*
Y877590D01*
G01X808869Y882570D02*
Y877588D01*
G01X807669Y882628D02*
Y880301D01*
G01X808869Y882570D02*
Y877588D01*
G01X832865Y880300D02*
Y877590D01*
G01X834066Y882570D02*
Y877588D01*
G01X832866Y882628D02*
Y880301D01*
G01X834066Y882570D02*
Y877588D01*
G01X808869Y882570D02*
Y877588D01*
G01X807668Y880300D02*
Y877590D01*
G01X807669Y882628D02*
Y880301D01*
G01X834066Y882570D02*
Y877588D01*
G01X832865Y880300D02*
Y877590D01*
G01X832866Y882628D02*
Y880301D01*
G01X840624Y177549D02*
G02X839924Y177950I384J1482D01*
G01X840324Y176387D02*
G03X841007Y176300I684J2644D01*
G01X841009Y177500D02*
G02X840624Y177549I-1J1533D01*
G01X840324Y176387D02*
G03X841007Y176300I684J2644D01*
G01X878907Y177500D02*
X841009D01*
G01X841007Y176300D02*
X878907D01*
G01X841007D02*
X878907D01*
G01Y177500D02*
X841009D01*
G01X840324Y176387D02*
G03X841007Y176300I684J2644D01*
G01X840624Y177549D02*
G02X839924Y177950I384J1482D01*
G01X841009Y177500D02*
G02X840624Y177549I-1J1533D01*
G01D02*
G02X839924Y177950I384J1482D01*
G01X841009Y177500D02*
G02X840624Y177549I-1J1533D01*
G01X845463Y880300D02*
Y877590D01*
G01X846664Y882570D02*
Y877588D01*
G01X845464Y882628D02*
Y880301D01*
G01X846664Y882570D02*
Y877588D01*
G01Y882570D02*
Y877588D01*
G01X845463Y880300D02*
Y877590D01*
G01X845464Y882628D02*
Y880301D01*
G01X906240Y-1329D02*
Y15637D01*
G01X896118Y-13149D02*
X907440Y-1827D01*
G01X895620Y-11949D02*
X906240Y-1329D01*
G01D02*
Y15637D01*
G01X895620Y-11949D02*
X906240Y-1329D01*
G01X896118Y-13149D02*
X907440Y-1827D01*
G01X906240Y15637D02*
X910404Y19801D01*
G01X906240Y15637D02*
X910404Y19801D01*
G01X907440Y-1827D02*
Y15139D01*
G01Y-1827D02*
Y15139D01*
G01X910901Y18600D02*
X966700D01*
G01X910404Y19801D02*
X966201D01*
G01X907440Y15139D02*
X910901Y18600D01*
G01X910404Y19801D02*
X966201D01*
G01X910901Y18600D02*
X966700D01*
G01X907440Y15139D02*
X910901Y18600D01*
G01X971061Y29681D02*
X991500D01*
G01X970563Y30881D02*
X991002D01*
G01X969128Y27748D02*
X971061Y29681D01*
G01X967928Y28246D02*
X970563Y30881D01*
G01X969128Y21028D02*
Y27748D01*
G01X967928Y21526D02*
Y28246D01*
G01X966700Y18600D02*
X969128Y21028D01*
G01X966202Y19800D02*
X967928Y21526D01*
G01X970563Y30881D02*
X991002D01*
G01X971061Y29681D02*
X991500D01*
G01X967928Y28246D02*
X970563Y30881D01*
G01X969128Y27748D02*
X971061Y29681D01*
G01X967928Y21526D02*
Y28246D01*
G01X969128Y21028D02*
Y27748D01*
G01X966202Y19800D02*
X967928Y21526D01*
G01X966700Y18600D02*
X969128Y21028D01*
G01X991500Y29681D02*
X1006084Y44265D01*
G01X991002Y30881D02*
X1005586Y45465D01*
G01X991002Y30881D02*
X1005586Y45465D01*
G01X991500Y29681D02*
X1006084Y44265D01*
G01D02*
X1009935D01*
G01X1005586Y45465D02*
X1010433D01*
G01X1005586D02*
X1010433D01*
G01X1006084Y44265D02*
X1009935D01*
G01X1028940Y36288D02*
X1033407Y40755D01*
G01X1028442Y37488D02*
X1032909Y41955D01*
G01X1021921Y36288D02*
X1028940D01*
G01X1022419Y37488D02*
X1028442D01*
G01X1019765Y38444D02*
X1021921Y36288D01*
G01X1020263Y39644D02*
X1022419Y37488D01*
G01X1015756Y38444D02*
X1019765D01*
G01X1016254Y39644D02*
X1020263D01*
G01X1009935Y44265D02*
X1015756Y38444D01*
G01X1010433Y45465D02*
X1016254Y39644D01*
G01X1028442Y37488D02*
X1032909Y41955D01*
G01X1028940Y36288D02*
X1033407Y40755D01*
G01X1022419Y37488D02*
X1028442D01*
G01X1021921Y36288D02*
X1028940D01*
G01X1020263Y39644D02*
X1022419Y37488D01*
G01X1019765Y38444D02*
X1021921Y36288D01*
G01X1016254Y39644D02*
X1020263D01*
G01X1015756Y38444D02*
X1019765D01*
G01X1010433Y45465D02*
X1016254Y39644D01*
G01X1009935Y44265D02*
X1015756Y38444D01*
G01X1038155Y40755D02*
X1045815Y48415D01*
G01X1037657Y41955D02*
X1044615Y48913D01*
G01X1033407Y40755D02*
X1038155D01*
G01X1032909Y41955D02*
X1037657D01*
G01D02*
X1044615Y48913D01*
G01X1038155Y40755D02*
X1045815Y48415D01*
G01X1032909Y41955D02*
X1037657D01*
G01X1033407Y40755D02*
X1038155D01*
G01X1036014Y880300D02*
Y877590D01*
G01X1037215Y882570D02*
Y877588D01*
G01X1036015Y882628D02*
Y880301D01*
G01X1037215Y882570D02*
Y877588D01*
G01Y882570D02*
Y877588D01*
G01X1036014Y880300D02*
Y877590D01*
G01X1036015Y882628D02*
Y880301D01*
G01X1070100Y23150D02*
X1076711D01*
G01Y21950D02*
X1070200D01*
G01X1076711D02*
X1070200D01*
G01X1070100Y23150D02*
X1076711D01*
G01X1074644Y35106D02*
X1079124D01*
G01Y33906D02*
X1074656D01*
G01X1079124D02*
X1074656D01*
G01X1074644Y35106D02*
X1079124D01*
G01X1062200Y23088D02*
X1063838D01*
G01X1062200Y21888D02*
X1063862D01*
G01X1062200D02*
X1063862D01*
G01X1062200Y23088D02*
X1063838D01*
G01X1066700Y35088D02*
X1068338D01*
G01X1066700Y33888D02*
X1068362D01*
G01X1066700D02*
X1068362D01*
G01X1066700Y35088D02*
X1068338D01*
G01X1066700D02*
X1068338D01*
G01X1066700Y33888D02*
X1068362D01*
G01X1066700D02*
X1068362D01*
G01X1066700Y35088D02*
X1068338D01*
G01X1062200Y23088D02*
X1063838D01*
G01X1062200Y21888D02*
X1063862D01*
G01X1062200D02*
X1063862D01*
G01X1062200Y23088D02*
X1063838D01*
G01X1079332Y69822D02*
X1064436D01*
G01X1078834Y71022D02*
X1064436D01*
G01X1078834D02*
X1064436D01*
G01X1079332Y69822D02*
X1064436D01*
G01X1052592Y69652D02*
X1056634D01*
G01X1052094Y70852D02*
X1056348D01*
G01X1045815Y62875D02*
X1052592Y69652D01*
G01X1044615Y63373D02*
X1052094Y70852D01*
G01X1045815Y48415D02*
Y62875D01*
G01X1044615Y48913D02*
Y63373D01*
G01X1052094Y70852D02*
X1056348D01*
G01X1052592Y69652D02*
X1056634D01*
G01X1044615Y63373D02*
X1052094Y70852D01*
G01X1045815Y62875D02*
X1052592Y69652D01*
G01X1044615Y48913D02*
Y63373D01*
G01X1045815Y48415D02*
Y62875D01*
G01X1048613Y880300D02*
Y877590D01*
G01X1049814Y882570D02*
Y877588D01*
G01X1048614Y882628D02*
Y880301D01*
G01X1049814Y882570D02*
Y877588D01*
G01X1073810Y880300D02*
Y877590D01*
G01X1075011Y882570D02*
Y877588D01*
G01X1073811Y882628D02*
Y880301D01*
G01X1075011Y882570D02*
Y877588D01*
G01X1049814Y882570D02*
Y877588D01*
G01X1048613Y880300D02*
Y877590D01*
G01X1048614Y882628D02*
Y880301D01*
G01X1075011Y882570D02*
Y877588D01*
G01X1073810Y880300D02*
Y877590D01*
G01X1073811Y882628D02*
Y880301D01*
G01X1080889Y21419D02*
X1197680D01*
G01X1197681Y20219D02*
X1080889D01*
G01X1078801Y22284D02*
G03X1080889Y21419I2088J2088D01*
G01Y20219D02*
G02X1077952Y21435I-1J4153D01*
G01X1076711Y23150D02*
G02X1078801Y22284I0J-2955D01*
G01X1077952Y21435D02*
G03X1076711Y21950I-1242J-1240D01*
G01X1077952Y21435D02*
G03X1076711Y21950I-1242J-1240D01*
G01Y23150D02*
G02X1078801Y22284I0J-2955D01*
G01X1080889Y20219D02*
G02X1077952Y21435I-1J4153D01*
G01X1078801Y22284D02*
G03X1080889Y21419I2088J2088D01*
G01X1197681Y20219D02*
X1080889D01*
G01Y21419D02*
X1197680D01*
G01X1108985Y35369D02*
G03X1110753Y36101I0J2500D01*
G01X1111603Y35253D02*
G02X1108986Y34169I-2617J2616D01*
G01X1088743Y35369D02*
X1108985D01*
G01X1108986Y34169D02*
X1088743D01*
G01X1087061Y34673D02*
G02X1088743Y35369I1682J-1684D01*
G01X1087909Y33823D02*
G02X1085378Y32774I-2532J2532D01*
G01X1088743Y34169D02*
G03X1087910Y33823I2J-1180D01*
G01X1085377Y33974D02*
G03X1087060Y34672I-1J2381D01*
G01X1087909Y33823D02*
G02X1085378Y32774I-2532J2532D01*
G01X1081856Y33974D02*
X1085377D01*
G01X1085378Y32774D02*
X1081856D01*
G01X1080490Y34540D02*
G03X1081856Y33974I1366J1365D01*
G01Y32774D02*
G02X1079641Y33691I-1J3132D01*
G01X1079124Y35106D02*
G02X1080490Y34540I0J-1931D01*
G01X1079641Y33691D02*
G03X1079124Y33906I-518J-516D01*
G01X1081856Y32774D02*
G02X1079641Y33691I-1J3132D01*
G01D02*
G03X1079124Y33906I-518J-516D01*
G01Y35106D02*
G02X1080490Y34540I0J-1931D01*
G01X1081856Y32774D02*
G02X1079641Y33691I-1J3132D01*
G01X1080490Y34540D02*
G03X1081856Y33974I1366J1365D01*
G01X1079124Y35106D02*
G02X1080490Y34540I0J-1931D01*
G01X1085378Y32774D02*
X1081856D01*
G01Y33974D02*
X1085377D01*
G01X1087909Y33823D02*
G02X1085378Y32774I-2532J2532D01*
G01X1087061Y34673D02*
G02X1088743Y35369I1682J-1684D01*
G01X1085377Y33974D02*
G03X1087060Y34672I-1J2381D01*
G01X1088743Y34169D02*
G03X1087910Y33823I2J-1180D01*
G01X1087061Y34673D02*
G02X1088743Y35369I1682J-1684D01*
G01X1108986Y34169D02*
X1088743D01*
G01Y35369D02*
X1108985D01*
G01X1111603Y35253D02*
G02X1108986Y34169I-2617J2616D01*
G01X1108985Y35369D02*
G03X1110753Y36101I0J2500D01*
G01X1109492Y71743D02*
X1105700D01*
G01X1109611Y72943D02*
X1105610D01*
G01X1110302Y71581D02*
X1109492Y71743D01*
G01X1110653Y72735D02*
X1109611Y72943D01*
G01D02*
X1105610D01*
G01X1109492Y71743D02*
X1105700D01*
G01X1110653Y72735D02*
X1109611Y72943D01*
G01X1110302Y71581D02*
X1109492Y71743D01*
G01X1110302Y71581D02*
X1109492Y71743D01*
G01X1105098Y95588D02*
X1079332Y69822D01*
G01X1104600Y96788D02*
X1078834Y71022D01*
G01X1104600Y96788D02*
X1078834Y71022D01*
G01X1105098Y95588D02*
X1079332Y69822D01*
G01X1127133Y95588D02*
X1105098D01*
G01X1112682Y96788D02*
X1104600D01*
G01X1112682D02*
X1104600D01*
G01X1127133Y95588D02*
X1105098D01*
G01X1127133D02*
X1105098D01*
G01X1127133D02*
X1105098D01*
G01X1086408Y880300D02*
Y877590D01*
G01X1087609Y882570D02*
Y877588D01*
G01X1086409Y882628D02*
Y880301D01*
G01X1087609Y882570D02*
Y877588D01*
G01X1099007Y880300D02*
Y877590D01*
G01X1100208Y882570D02*
Y877588D01*
G01X1099008Y882628D02*
Y880301D01*
G01X1100208Y882570D02*
Y877588D01*
G01X1087609Y882570D02*
Y877588D01*
G01X1086408Y880300D02*
Y877590D01*
G01X1086409Y882628D02*
Y880301D01*
G01X1100208Y882570D02*
Y877588D01*
G01X1099007Y880300D02*
Y877590D01*
G01X1099008Y882628D02*
Y880301D01*
G01X1110753Y36101D02*
X1125400Y50748D01*
G01X1125781Y49431D02*
X1111603Y35253D01*
G01X1125781Y49431D02*
X1111603Y35253D01*
G01X1110753Y36101D02*
X1125400Y50748D01*
G01X1111379Y72435D02*
X1110653Y72735D01*
G01X1110811Y71370D02*
X1110302Y71581D01*
G01X1111379Y72435D02*
X1110653Y72735D01*
G01X1111292Y71050D02*
X1110811Y71370D01*
G01X1111902Y72087D02*
X1111379Y72435D01*
G01X1122086Y60256D02*
X1111292Y71050D01*
G01X1122935Y61105D02*
X1112005Y72035D01*
G01X1124396Y59300D02*
G02X1122086Y60256I-1J3266D01*
G01X1124396Y60500D02*
G02X1122935Y61105I0J2066D01*
G01X1144100Y59300D02*
X1124396D01*
G01X1144100Y60500D02*
X1124396D01*
G01X1111379Y72435D02*
X1110653Y72735D01*
G01X1110811Y71370D02*
X1110302Y71581D01*
G01X1111902Y72087D02*
X1111379Y72435D01*
G01X1111292Y71050D02*
X1110811Y71370D01*
G01X1122935Y61105D02*
X1112005Y72035D01*
G01X1122086Y60256D02*
X1111292Y71050D01*
G01X1124396Y60500D02*
G02X1122935Y61105I0J2066D01*
G01X1124396Y59300D02*
G02X1122086Y60256I-1J3266D01*
G01X1144100Y60500D02*
X1124396D01*
G01X1144100Y59300D02*
X1124396D01*
G01X1111500Y84878D02*
X1112869Y83509D01*
G01X1112114Y82566D02*
X1110635Y84045D01*
G01X1111000Y86144D02*
G03X1111500Y84878I1853J0D01*
G01X1110623Y84058D02*
G02X1109800Y86144I2230J2085D01*
G01X1111000Y86600D02*
Y86144D01*
G01X1109800D02*
Y86600D01*
G01X1113500Y89100D02*
G03X1111000Y86600I0J-2500D01*
G01X1109800D02*
G02X1113500Y90300I3700J0D01*
G01X1149464Y89100D02*
X1113500D01*
G01Y90300D02*
X1149399D01*
G01X1113500D02*
X1149399D01*
G01X1149464Y89100D02*
X1113500D01*
G01X1109800Y86600D02*
G02X1113500Y90300I3700J0D01*
G01Y89100D02*
G03X1111000Y86600I0J-2500D01*
G01X1109800Y86144D02*
Y86600D01*
G01X1111000D02*
Y86144D01*
G01X1110623Y84058D02*
G02X1109800Y86144I2230J2085D01*
G01X1111000D02*
G03X1111500Y84878I1853J0D01*
G01X1112114Y82566D02*
X1110635Y84045D01*
G01X1111500Y84878D02*
X1112869Y83509D01*
G01X1117134Y96788D02*
X1115520D01*
G01X1125000D02*
X1119972D01*
G01X1117134D02*
X1115520D01*
G01X1125000D02*
X1119972D01*
G01X1111605Y880300D02*
Y877590D01*
G01X1112806Y882570D02*
Y877588D01*
G01X1111606Y882628D02*
Y880301D01*
G01X1112806Y882570D02*
Y877588D01*
G01X1124203Y880300D02*
Y877590D01*
G01X1125404Y882570D02*
Y877588D01*
G01X1124204Y882628D02*
Y880301D01*
G01X1125404Y882570D02*
Y877588D01*
G01X1136802Y880300D02*
Y877590D01*
G01X1138003Y882570D02*
Y877588D01*
G01X1136803Y882628D02*
Y880301D01*
G01X1138003Y882570D02*
Y877588D01*
G01X1112806Y882570D02*
Y877588D01*
G01X1111605Y880300D02*
Y877590D01*
G01X1111606Y882628D02*
Y880301D01*
G01X1125404Y882570D02*
Y877588D01*
G01X1124203Y880300D02*
Y877590D01*
G01X1124204Y882628D02*
Y880301D01*
G01X1138003Y882570D02*
Y877588D01*
G01X1136802Y880300D02*
Y877590D01*
G01X1136803Y882628D02*
Y880301D01*
G01X1161295Y72920D02*
X1158087Y80884D01*
G01X1159201Y81333D02*
X1162409Y73369D01*
G01X1162466Y70668D02*
G02X1161295Y72920I11044J7173D01*
G01X1162409Y73369D02*
G03X1163473Y71322I11102J4471D01*
G01X1167127Y63492D02*
X1162466Y70668D01*
G01X1163473Y71322D02*
X1168134Y64146D01*
G01X1168621Y61998D02*
G02X1167127Y63492I2769J4263D01*
G01X1168134Y64146D02*
G03X1169275Y63005I3256J2115D01*
G01X1171157Y60350D02*
X1168621Y61998D01*
G01X1169275Y63005D02*
X1171811Y61357D01*
G01X1173252Y59483D02*
G02X1171157Y60350I1289J6078D01*
G01X1171811Y61357D02*
G03X1173501Y60657I2731J4204D01*
G01X1179915Y58067D02*
X1173252Y59483D01*
G01X1173501Y60657D02*
X1180165Y59241D01*
G01X1173501Y60657D02*
X1180165Y59241D01*
G01X1179915Y58067D02*
X1173252Y59483D01*
G01X1171811Y61357D02*
G03X1173501Y60657I2731J4204D01*
G01X1173252Y59483D02*
G02X1171157Y60350I1289J6078D01*
G01X1169275Y63005D02*
X1171811Y61357D01*
G01X1171157Y60350D02*
X1168621Y61998D01*
G01X1168134Y64146D02*
G03X1169275Y63005I3256J2115D01*
G01X1168621Y61998D02*
G02X1167127Y63492I2769J4263D01*
G01X1163473Y71322D02*
X1168134Y64146D01*
G01X1167127Y63492D02*
X1162466Y70668D01*
G01X1162409Y73369D02*
G03X1163473Y71322I11102J4471D01*
G01X1162466Y70668D02*
G02X1161295Y72920I11044J7173D01*
G01X1159201Y81333D02*
X1162409Y73369D01*
G01X1161295Y72920D02*
X1158087Y80884D01*
G01X1145382Y58769D02*
G03X1144100Y59300I-1282J-1282D01*
G01X1146232Y59617D02*
G03X1144100Y60500I-2132J-2132D01*
G01X1147183Y57451D02*
G03X1146324Y59525I-2934J0D01*
G01X1145983Y57450D02*
G03X1145475Y58676I-1734J0D01*
G01X1146232Y59617D02*
G03X1144100Y60500I-2132J-2132D01*
G01X1147183Y57451D02*
G03X1146324Y59525I-2934J0D01*
G01X1145983Y57300D02*
Y57450D01*
G01X1147183Y49331D02*
Y57451D01*
G01X1145485Y56098D02*
G03X1145983Y57300I-1202J1202D01*
G01X1147183Y57451D02*
G03X1146324Y59525I-2934J0D01*
G01X1146232Y59617D02*
G03X1144100Y60500I-2132J-2132D01*
G01X1145382Y58769D02*
G03X1144100Y59300I-1282J-1282D01*
G01X1145983Y57450D02*
G03X1145475Y58676I-1734J0D01*
G01X1147183Y57451D02*
G03X1146324Y59525I-2934J0D01*
G01X1145382Y58769D02*
G03X1144100Y59300I-1282J-1282D01*
G01X1145983Y57450D02*
G03X1145475Y58676I-1734J0D01*
G01X1145485Y56098D02*
G03X1145983Y57300I-1202J1202D01*
G01X1147183Y49331D02*
Y57451D01*
G01X1145983Y57300D02*
Y57450D01*
G01X1150939Y88462D02*
G03X1149464Y89100I-1541J-1539D01*
G01X1149400Y90301D02*
G02X1151788Y89311I-1J-3378D01*
G01X1157247Y82155D02*
X1150939Y88462D01*
G01X1151788Y89311D02*
X1158096Y83004D01*
G01X1158087Y80884D02*
G03X1157247Y82155I-3532J-1421D01*
G01X1158096Y83004D02*
G02X1159201Y81333I-3540J-3542D01*
G01X1158096Y83004D02*
G02X1159201Y81333I-3540J-3542D01*
G01X1158087Y80884D02*
G03X1157247Y82155I-3532J-1421D01*
G01X1151788Y89311D02*
X1158096Y83004D01*
G01X1157247Y82155D02*
X1150939Y88462D01*
G01X1149400Y90301D02*
G02X1151788Y89311I-1J-3378D01*
G01X1150939Y88462D02*
G03X1149464Y89100I-1541J-1539D01*
G01X1149400Y880300D02*
Y877590D01*
G01X1150601Y882570D02*
Y877588D01*
G01X1149401Y882628D02*
Y880301D01*
G01X1150601Y882570D02*
Y877588D01*
G01X1161999Y880300D02*
Y877590D01*
G01X1163200Y882570D02*
Y877588D01*
G01X1162000Y882628D02*
Y880301D01*
G01X1163200Y882570D02*
Y877588D01*
G01X1150601Y882570D02*
Y877588D01*
G01X1149400Y880300D02*
Y877590D01*
G01X1149401Y882628D02*
Y880301D01*
G01X1163200Y882570D02*
Y877588D01*
G01X1161999Y880300D02*
Y877590D01*
G01X1162000Y882628D02*
Y880301D01*
G01X1209307Y33046D02*
Y46495D01*
G01X1210507D02*
Y33045D01*
G01X1208575Y31278D02*
G03X1209307Y33046I-1768J1768D01*
G01X1210507Y33045D02*
G02X1209423Y30428I-3700J0D01*
G01X1199448Y22151D02*
X1208575Y31278D01*
G01X1209423Y30428D02*
X1200298Y21303D01*
G01X1197680Y21419D02*
G03X1199448Y22151I0J2500D01*
G01X1200298Y21303D02*
G02X1197681Y20219I-2617J2616D01*
G01X1200298Y21303D02*
G02X1197681Y20219I-2617J2616D01*
G01X1197680Y21419D02*
G03X1199448Y22151I0J2500D01*
G01X1209423Y30428D02*
X1200298Y21303D01*
G01X1199448Y22151D02*
X1208575Y31278D01*
G01X1210507Y33045D02*
G02X1209423Y30428I-3700J0D01*
G01X1208575Y31278D02*
G03X1209307Y33046I-1768J1768D01*
G01X1210507Y46495D02*
Y33045D01*
G01X1209307Y33046D02*
Y46495D01*
G01X1180955Y56783D02*
G03X1179915Y58067I-1313J0D01*
G01X1180165Y59241D02*
G02X1182155Y56783I-523J-2458D01*
G01X1180955Y55227D02*
Y56783D01*
G01X1182155D02*
Y55228D01*
G01X1180927Y54663D02*
G03X1180954Y55227I-5882J564D01*
G01X1182123Y54549D02*
G02X1182001Y53752I-7078J676D01*
G01X1182155Y55228D02*
G02X1182123Y54549I-7110J-5D01*
G01X1180826Y54002D02*
G03X1180927Y54663I-5782J1222D01*
G01X1182123Y54549D02*
G02X1182001Y53752I-7078J676D01*
G01X1182155Y55228D02*
G02X1182123Y54549I-7110J-5D01*
G01D02*
G02X1182001Y53752I-7078J676D01*
G01X1180927Y54663D02*
G03X1180954Y55227I-5882J564D01*
G01X1180826Y54002D02*
G03X1180927Y54663I-5782J1222D01*
G01X1182155Y55228D02*
G02X1182123Y54549I-7110J-5D01*
G01X1180927Y54663D02*
G03X1180954Y55227I-5882J564D01*
G01X1180826Y54002D02*
G03X1180927Y54663I-5782J1222D01*
G01X1182155Y56783D02*
Y55228D01*
G01X1180955Y55227D02*
Y56783D01*
G01X1180165Y59241D02*
G02X1182155Y56783I-523J-2458D01*
G01X1180955D02*
G03X1179915Y58067I-1313J0D01*
G01X1210523Y49432D02*
X1213326Y52235D01*
G01X1209307Y46495D02*
G02X1210523Y49432I4153J1D01*
G01X1211372Y48583D02*
G03X1210507Y46495I2088J-2088D01*
G01X1211372Y48583D02*
G03X1210507Y46495I2088J-2088D01*
G01X1209307D02*
G02X1210523Y49432I4153J1D01*
G01D02*
X1213326Y52235D01*
G01X1184046Y880300D02*
Y877590D01*
G01X1185247Y882570D02*
Y877588D01*
G01X1184047Y882628D02*
Y880301D01*
G01X1185247Y882570D02*
Y877588D01*
G01X1196645Y882628D02*
Y869400D01*
G01X1197845Y882570D02*
Y869400D01*
G01X1185247Y882570D02*
Y877588D01*
G01X1184046Y880300D02*
Y877590D01*
G01X1184047Y882628D02*
Y880301D01*
G01X1197845Y882570D02*
Y869400D01*
G01X1196645Y882628D02*
Y869400D01*
G01X1212661Y49872D02*
X1211372Y48583D01*
G01X1212661Y49872D02*
X1211372Y48583D01*
G01X1228140Y880300D02*
Y877590D01*
G01X1229341Y882570D02*
Y877588D01*
G01X1228141Y882628D02*
Y880301D01*
G01X1229341Y882570D02*
Y877588D01*
G01X1240739Y880300D02*
Y877590D01*
G01X1241940Y882570D02*
Y877588D01*
G01X1240740Y882628D02*
Y880301D01*
G01X1241940Y882570D02*
Y877588D01*
G01X1229341Y882570D02*
Y877588D01*
G01X1228140Y880300D02*
Y877590D01*
G01X1228141Y882628D02*
Y880301D01*
G01X1241940Y882570D02*
Y877588D01*
G01X1240739Y880300D02*
Y877590D01*
G01X1240740Y882628D02*
Y880301D01*
G01X1253337Y880300D02*
Y877590D01*
G01X1254538Y882570D02*
Y877588D01*
G01X1253338Y882628D02*
Y880301D01*
G01X1254538Y882570D02*
Y877588D01*
G01X1265936Y880300D02*
Y877590D01*
G01X1267137Y882570D02*
Y877588D01*
G01X1265937Y882628D02*
Y880301D01*
G01X1267137Y882570D02*
Y877588D01*
G01X1254538Y882570D02*
Y877588D01*
G01X1253337Y880300D02*
Y877590D01*
G01X1253338Y882628D02*
Y880301D01*
G01X1267137Y882570D02*
Y877588D01*
G01X1265936Y880300D02*
Y877590D01*
G01X1265937Y882628D02*
Y880301D01*
G01X1291133Y880300D02*
Y877590D01*
G01X1292334Y882570D02*
Y877588D01*
G01X1291134Y882628D02*
Y880301D01*
G01X1292334Y882570D02*
Y877588D01*
G01X1303731Y880300D02*
Y877590D01*
G01X1304932Y882570D02*
Y877588D01*
G01X1303732Y882628D02*
Y880301D01*
G01X1304932Y882570D02*
Y877588D01*
G01X1279735Y882570D02*
Y877588D01*
G01X1278534Y880300D02*
Y877590D01*
G01X1278535Y882628D02*
Y880301D01*
G01X1292334Y882570D02*
Y877588D01*
G01X1291133Y880300D02*
Y877590D01*
G01X1291134Y882628D02*
Y880301D01*
G01X1304932Y882570D02*
Y877588D01*
G01X1303731Y880300D02*
Y877590D01*
G01X1303732Y882628D02*
Y880301D01*
G01X1278534Y880300D02*
Y877590D01*
G01X1279735Y882570D02*
Y877588D01*
G01X1278535Y882628D02*
Y880301D01*
G01X1279735Y882570D02*
Y877588D01*
G01X1316329Y880300D02*
Y877590D01*
G01X1317530Y882570D02*
Y877588D01*
G01X1316330Y882628D02*
Y880301D01*
G01X1317530Y882570D02*
Y877588D01*
G01X1328928Y880300D02*
Y877590D01*
G01X1330129Y882570D02*
Y877588D01*
G01X1328929Y882628D02*
Y880301D01*
G01X1330129Y882570D02*
Y877588D01*
G01X1341526Y880300D02*
Y877590D01*
G01X1342727Y882570D02*
Y877588D01*
G01X1341527Y882628D02*
Y880301D01*
G01X1342727Y882570D02*
Y877588D01*
G01X1317530Y882570D02*
Y877588D01*
G01X1316329Y880300D02*
Y877590D01*
G01X1316330Y882628D02*
Y880301D01*
G01X1330129Y882570D02*
Y877588D01*
G01X1328928Y880300D02*
Y877590D01*
G01X1328929Y882628D02*
Y880301D01*
G01X1342727Y882570D02*
Y877588D01*
G01X1341526Y880300D02*
Y877590D01*
G01X1341527Y882628D02*
Y880301D01*
M02*
